FILE_TYPE = MACRO_DRAWING;
SET COLOR_WIRE YELLOW;
SET COLOR_PROP MONO;
SET COLOR_DOT WHITE;
SET COLOR_ARC YELLOW;
SET COLOR_BODY GREEN;
SET COLOR_NOTE MONO;
SET PROP_DISPLAY VALUE;
SET PAGE_NUMBER P185;
FORCEADD OFFPAGE..1
(-3875 2200);
FORCEPROP 2 LAST $XR0 116 
J 0
(-4127 2200);
DISPLAY 0.638298 (-4127 2200);
PAINT MONO (-4127 2200);
FORCEPROP 2 LAST PATH I100
J 0
(-4125 2250);
DISPLAY 1.021277 (-4125 2250);
PAINT ORANGE (-4125 2250);
DISPLAY INVISIBLE (-4125 2250);
FORCEPROP 2 LAST CDS_LIB mstr_standard
J 0
(-3875 2200);
PAINT ORANGE (-3875 2200);
DISPLAY INVISIBLE (-3875 2200);
FORCEPROP 1 LAST COMMENT_BODY TRUE
J 0
(-3750 2100);
DISPLAY 0.872340 (-3750 2100);
PAINT GREEN (-3750 2100);
DISPLAY INVISIBLE (-3750 2100);
FORCEPROP 1 LAST OFFPAGE TRUE
J 0
(-3550 2075);
DISPLAY 0.872340 (-3550 2075);
PAINT GREEN (-3550 2075);
DISPLAY INVISIBLE (-3550 2075);
FORCEADD OFFPAGE..1
(-3875 1925);
FORCEPROP 2 LAST $XR0 116 
J 0
(-4127 1925);
DISPLAY 0.638298 (-4127 1925);
PAINT MONO (-4127 1925);
FORCEPROP 2 LAST PATH I101
J 0
(-4125 1975);
DISPLAY 1.021277 (-4125 1975);
PAINT ORANGE (-4125 1975);
DISPLAY INVISIBLE (-4125 1975);
FORCEPROP 2 LAST CDS_LIB mstr_standard
J 0
(-3875 1925);
PAINT ORANGE (-3875 1925);
DISPLAY INVISIBLE (-3875 1925);
FORCEPROP 1 LAST COMMENT_BODY TRUE
J 0
(-3750 1825);
DISPLAY 0.872340 (-3750 1825);
PAINT GREEN (-3750 1825);
DISPLAY INVISIBLE (-3750 1825);
FORCEPROP 1 LAST OFFPAGE TRUE
J 0
(-3550 1800);
DISPLAY 0.872340 (-3550 1800);
PAINT GREEN (-3550 1800);
DISPLAY INVISIBLE (-3550 1800);
FORCEADD OFFPAGE..1
(-3875 1700);
FORCEPROP 2 LAST $XR0 116 
J 0
(-4127 1700);
DISPLAY 0.638298 (-4127 1700);
PAINT MONO (-4127 1700);
FORCEPROP 2 LAST PATH I102
J 0
(-4125 1750);
DISPLAY 1.021277 (-4125 1750);
PAINT ORANGE (-4125 1750);
DISPLAY INVISIBLE (-4125 1750);
FORCEPROP 2 LAST CDS_LIB mstr_standard
J 0
(-3875 1700);
PAINT ORANGE (-3875 1700);
DISPLAY INVISIBLE (-3875 1700);
FORCEPROP 1 LAST COMMENT_BODY TRUE
J 0
(-3750 1600);
DISPLAY 0.872340 (-3750 1600);
PAINT GREEN (-3750 1600);
DISPLAY INVISIBLE (-3750 1600);
FORCEPROP 1 LAST OFFPAGE TRUE
J 0
(-3550 1575);
DISPLAY 0.872340 (-3550 1575);
PAINT GREEN (-3550 1575);
DISPLAY INVISIBLE (-3550 1575);
FORCEADD OFFPAGE..1
(-3875 1475);
FORCEPROP 2 LAST $XR0 116 
J 0
(-4127 1475);
DISPLAY 0.638298 (-4127 1475);
PAINT MONO (-4127 1475);
FORCEPROP 2 LAST PATH I103
J 0
(-4125 1525);
DISPLAY 1.021277 (-4125 1525);
PAINT ORANGE (-4125 1525);
DISPLAY INVISIBLE (-4125 1525);
FORCEPROP 2 LAST CDS_LIB mstr_standard
J 0
(-3875 1475);
PAINT ORANGE (-3875 1475);
DISPLAY INVISIBLE (-3875 1475);
FORCEPROP 1 LAST COMMENT_BODY TRUE
J 0
(-3750 1375);
DISPLAY 0.872340 (-3750 1375);
PAINT GREEN (-3750 1375);
DISPLAY INVISIBLE (-3750 1375);
FORCEPROP 1 LAST OFFPAGE TRUE
J 0
(-3550 1350);
DISPLAY 0.872340 (-3550 1350);
PAINT GREEN (-3550 1350);
DISPLAY INVISIBLE (-3550 1350);
FORCEADD OFFPAGE..5
(-3875 1275);
FORCEPROP 2 LAST $XR0 116 
J 0
(-4130 1275);
DISPLAY 0.638298 (-4130 1275);
PAINT MONO (-4130 1275);
FORCEPROP 2 LAST PATH I104
J 0
(-4150 1325);
DISPLAY 1.021277 (-4150 1325);
PAINT ORANGE (-4150 1325);
DISPLAY INVISIBLE (-4150 1325);
FORCEPROP 2 LAST CDS_LIB mstr_standard
J 0
(-3875 1275);
PAINT ORANGE (-3875 1275);
DISPLAY INVISIBLE (-3875 1275);
FORCEPROP 1 LAST COMMENT_BODY TRUE
J 0
(-3775 1200);
DISPLAY 0.872340 (-3775 1200);
PAINT GREEN (-3775 1200);
DISPLAY INVISIBLE (-3775 1200);
FORCEPROP 1 LAST OFFPAGE TRUE
J 0
(-3550 1150);
DISPLAY 0.872340 (-3550 1150);
PAINT GREEN (-3550 1150);
DISPLAY INVISIBLE (-3550 1150);
FORCEADD RES..1
(-2900 1050);
FORCEPROP 1 LAST LOCATION R8F18
J 0
(-3400 1050);
DISPLAY 0.617021 (-3400 1050);
PAINT AQUA (-3400 1050);
FORCEPROP 1 LAST VALUE 0.0
J 1
(-3200 1050);
DISPLAY 0.617021 (-3200 1050);
PAINT SKYBLUE (-3200 1050);
FORCEPROP 1 LAST TOLERANCE 5%
J 0
(-3100 1050);
DISPLAY 0.617021 (-3100 1050);
PAINT SKYBLUE (-3100 1050);
FORCEPROP 1 LASTPIN (-3000 1050) $PN 1
J 0
(-2988 1062);
DISPLAY 0.617021 (-2988 1062);
PAINT ORANGE (-2988 1062);
FORCEPROP 1 LASTPIN (-2800 1050) $PN 2
J 0
(-2838 1062);
DISPLAY 0.617021 (-2838 1062);
PAINT ORANGE (-2838 1062);
FORCEPROP 1 LAST MATERIAL CHIP
J 0
(-2775 1050);
DISPLAY 0.617021 (-2775 1050);
PAINT SKYBLUE (-2775 1050);
FORCEPROP 1 LAST WATTAGE 1/16W
J 2
(-2550 1050);
DISPLAY 0.617021 (-2550 1050);
PAINT SKYBLUE (-2550 1050);
FORCEPROP 1 LAST PACK_TYPE 0402
J 2
(-2425 1050);
DISPLAY 0.617021 (-2425 1050);
PAINT SKYBLUE (-2425 1050);
FORCEPROP 1 LAST PART_NUMBER G21497-005
J 2
(-2150 1050);
DISPLAY 0.617021 (-2150 1050);
PAINT BLUE (-2150 1050);
FORCEPROP 2 LAST CDS_LOCATION R8F18
J 0
(-3400 1050);
DISPLAY 0.617021 (-3400 1050);
PAINT AQUA (-3400 1050);
DISPLAY INVISIBLE (-3400 1050);
FORCEPROP 1 LAST PATH I105
J 0
(-2950 1200);
DISPLAY 0.978723 (-2950 1200);
PAINT WHITE (-2950 1200);
DISPLAY INVISIBLE (-2950 1200);
FORCEPROP 2 LAST SEC 1
J 0
(-2950 1250);
DISPLAY 0.680851 (-2950 1250);
PAINT MONO (-2950 1250);
DISPLAY INVISIBLE (-2950 1250);
FORCEPROP 2 LAST CDS_LIB mstr_discrete
J 0
(-2900 1050);
PAINT ORANGE (-2900 1050);
DISPLAY INVISIBLE (-2900 1050);
FORCEPROP 2 LAST SEC_TYPE 0402
J 0
(-2950 1250);
DISPLAY 1.021277 (-2950 1250);
PAINT ORANGE (-2950 1250);
DISPLAY INVISIBLE (-2950 1250);
FORCEPROP 0 LAST ROOM M_2
J 0
(-2150 1100);
DISPLAY 1.021277 (-2150 1100);
PAINT ORANGE (-2150 1100);
DISPLAY INVISIBLE (-2150 1100);
FORCEPROP 0 LAST BOM_COST ST_FLASH
J 0
(-2150 1150);
DISPLAY 1.021277 (-2150 1150);
PAINT ORANGE (-2150 1150);
DISPLAY INVISIBLE (-2150 1150);
FORCEADD RES..1
(-2875 600);
FORCEPROP 1 LAST VALUE 0.0
J 1
(-3225 600);
DISPLAY 0.617021 (-3225 600);
PAINT SKYBLUE (-3225 600);
FORCEPROP 1 LAST LOCATION R8F21
J 0
(-3375 600);
DISPLAY 0.617021 (-3375 600);
PAINT AQUA (-3375 600);
FORCEPROP 1 LAST TOLERANCE 5%
J 0
(-3050 600);
DISPLAY 0.617021 (-3050 600);
PAINT SKYBLUE (-3050 600);
FORCEPROP 1 LASTPIN (-2975 600) $PN 1
J 0
(-2963 612);
DISPLAY 0.617021 (-2963 612);
PAINT ORANGE (-2963 612);
FORCEPROP 1 LASTPIN (-2775 600) $PN 2
J 0
(-2813 612);
DISPLAY 0.617021 (-2813 612);
PAINT ORANGE (-2813 612);
FORCEPROP 1 LAST MATERIAL CHIP
J 0
(-2750 600);
DISPLAY 0.617021 (-2750 600);
PAINT SKYBLUE (-2750 600);
FORCEPROP 1 LAST WATTAGE 1/16W
J 2
(-2525 600);
DISPLAY 0.617021 (-2525 600);
PAINT SKYBLUE (-2525 600);
FORCEPROP 1 LAST PART_NUMBER G21497-005
J 2
(-2125 600);
DISPLAY 0.617021 (-2125 600);
PAINT BLUE (-2125 600);
FORCEPROP 1 LAST PACK_TYPE 0402
J 2
(-2400 600);
DISPLAY 0.617021 (-2400 600);
PAINT SKYBLUE (-2400 600);
FORCEPROP 2 LAST CDS_LOCATION R8F21
J 0
(-3375 600);
DISPLAY 0.617021 (-3375 600);
PAINT AQUA (-3375 600);
DISPLAY INVISIBLE (-3375 600);
FORCEPROP 2 LAST CDS_LIB mstr_discrete
J 0
(-2875 600);
PAINT ORANGE (-2875 600);
DISPLAY INVISIBLE (-2875 600);
FORCEPROP 1 LAST PATH I106
J 0
(-2925 750);
DISPLAY 0.978723 (-2925 750);
PAINT WHITE (-2925 750);
DISPLAY INVISIBLE (-2925 750);
FORCEPROP 2 LAST SEC_TYPE 0402
J 0
(-2925 800);
DISPLAY 1.021277 (-2925 800);
PAINT ORANGE (-2925 800);
DISPLAY INVISIBLE (-2925 800);
FORCEPROP 2 LAST SEC 1
J 0
(-2925 800);
DISPLAY 0.680851 (-2925 800);
PAINT MONO (-2925 800);
DISPLAY INVISIBLE (-2925 800);
FORCEPROP 0 LAST BOM_COST ST_FLASH
J 0
(-2125 700);
DISPLAY 1.021277 (-2125 700);
PAINT ORANGE (-2125 700);
DISPLAY INVISIBLE (-2125 700);
FORCEPROP 0 LAST ROOM M_2
J 0
(-2125 650);
DISPLAY 1.021277 (-2125 650);
PAINT ORANGE (-2125 650);
DISPLAY INVISIBLE (-2125 650);
FORCEADD OFFPAGE..5
(-3875 1050);
FORCEPROP 2 LAST $XR0 116 
J 0
(-4130 1050);
DISPLAY 0.638298 (-4130 1050);
PAINT MONO (-4130 1050);
FORCEPROP 2 LAST PATH I107
J 0
(-4150 1100);
DISPLAY 1.021277 (-4150 1100);
PAINT ORANGE (-4150 1100);
DISPLAY INVISIBLE (-4150 1100);
FORCEPROP 1 LAST COMMENT_BODY TRUE
J 0
(-3775 975);
DISPLAY 0.872340 (-3775 975);
PAINT GREEN (-3775 975);
DISPLAY INVISIBLE (-3775 975);
FORCEPROP 1 LAST OFFPAGE TRUE
J 0
(-3550 925);
DISPLAY 0.872340 (-3550 925);
PAINT GREEN (-3550 925);
DISPLAY INVISIBLE (-3550 925);
FORCEPROP 2 LAST CDS_LIB mstr_standard
J 0
(-3875 1050);
PAINT ORANGE (-3875 1050);
DISPLAY INVISIBLE (-3875 1050);
FORCEADD OFFPAGE..5
(-3875 850);
FORCEPROP 2 LAST $XR0 116 
J 0
(-4130 850);
DISPLAY 0.638298 (-4130 850);
PAINT MONO (-4130 850);
FORCEPROP 2 LAST PATH I108
J 0
(-4150 900);
DISPLAY 1.021277 (-4150 900);
PAINT ORANGE (-4150 900);
DISPLAY INVISIBLE (-4150 900);
FORCEPROP 2 LAST CDS_LIB mstr_standard
J 0
(-3875 850);
PAINT ORANGE (-3875 850);
DISPLAY INVISIBLE (-3875 850);
FORCEPROP 1 LAST COMMENT_BODY TRUE
J 0
(-3775 775);
DISPLAY 0.872340 (-3775 775);
PAINT GREEN (-3775 775);
DISPLAY INVISIBLE (-3775 775);
FORCEPROP 1 LAST OFFPAGE TRUE
J 0
(-3550 725);
DISPLAY 0.872340 (-3550 725);
PAINT GREEN (-3550 725);
DISPLAY INVISIBLE (-3550 725);
FORCEADD OFFPAGE..5
(-3875 600);
FORCEPROP 2 LAST $XR0 116 
J 0
(-4130 600);
DISPLAY 0.638298 (-4130 600);
PAINT MONO (-4130 600);
FORCEPROP 2 LAST PATH I109
J 0
(-4150 650);
DISPLAY 1.021277 (-4150 650);
PAINT ORANGE (-4150 650);
DISPLAY INVISIBLE (-4150 650);
FORCEPROP 2 LAST CDS_LIB mstr_standard
J 0
(-3875 600);
PAINT ORANGE (-3875 600);
DISPLAY INVISIBLE (-3875 600);
FORCEPROP 1 LAST COMMENT_BODY TRUE
J 0
(-3775 525);
DISPLAY 0.872340 (-3775 525);
PAINT GREEN (-3775 525);
DISPLAY INVISIBLE (-3775 525);
FORCEPROP 1 LAST OFFPAGE TRUE
J 0
(-3550 475);
DISPLAY 0.872340 (-3550 475);
PAINT GREEN (-3550 475);
DISPLAY INVISIBLE (-3550 475);
FORCEADD TTL1G07_A..1
(-6375 1250);
FORCEPROP 2 LASTPIN (-6475 1250) $PN 2
J 2
(-6485 1260);
DISPLAY 0.617021 (-6485 1260);
PAINT ORANGE (-6485 1260);
FORCEPROP 1 LAST LOCATION U2P1
J 0
(-6425 1450);
DISPLAY 0.617021 (-6425 1450);
PAINT AQUA (-6425 1450);
FORCEPROP 1 LAST MATERIAL IC
J 0
(-6425 1400);
DISPLAY 0.617021 (-6425 1400);
PAINT SKYBLUE (-6425 1400);
FORCEPROP 2 LASTPIN (-6225 1250) $PN 4
J 0
(-6215 1260);
DISPLAY 0.617021 (-6215 1260);
PAINT ORANGE (-6215 1260);
FORCEPROP 1 LAST POWER_GROUP VCC=P3V3_STBY;GND=GND
J 1
(-6425 1060);
DISPLAY 0.617021 (-6425 1060);
PAINT ORANGE (-6425 1060);
FORCEPROP 1 LAST PART_NUMBER C88419-001
J 0
(-6425 1115);
DISPLAY 0.617021 (-6425 1115);
PAINT BLUE (-6425 1115);
FORCEPROP 1 LAST VALUE 74LVC1G07
J 1
(-6375 1350);
DISPLAY 0.617021 (-6375 1350);
PAINT SKYBLUE (-6375 1350);
FORCEPROP 2 LAST SEC 1
J 0
(-6425 1500);
DISPLAY 0.680851 (-6425 1500);
PAINT MONO (-6425 1500);
DISPLAY INVISIBLE (-6425 1500);
FORCEPROP 1 LAST PATH I110
J 0
(-6325 1300);
DISPLAY 0.978723 (-6325 1300);
PAINT WHITE (-6325 1300);
DISPLAY INVISIBLE (-6325 1300);
FORCEPROP 2 LAST CDS_LIB mstr_ttl
J 0
(-6375 1250);
PAINT ORANGE (-6375 1250);
DISPLAY INVISIBLE (-6375 1250);
FORCEPROP 1 LAST PACK_TYPE SOP
J 0
(-6425 1500);
DISPLAY 0.978723 (-6425 1500);
PAINT SKYBLUE (-6425 1500);
DISPLAY INVISIBLE (-6425 1500);
FORCEPROP 2 LAST SEC_TYPE SOP
J 0
(-6425 1500);
DISPLAY 1.021277 (-6425 1500);
PAINT ORANGE (-6425 1500);
DISPLAY INVISIBLE (-6425 1500);
FORCEPROP 0 LAST BOM_COST ST_FLASH
J 0
(-6425 1650);
DISPLAY 1.021277 (-6425 1650);
PAINT ORANGE (-6425 1650);
DISPLAY INVISIBLE (-6425 1650);
FORCEPROP 0 LAST ROOM M_2
J 0
(-6425 1550);
DISPLAY 1.021277 (-6425 1550);
PAINT ORANGE (-6425 1550);
DISPLAY INVISIBLE (-6425 1550);
FORCEADD RES..2
(-6725 1525);
FORCEPROP 1 LASTPIN (-6725 1425) $PN 2
J 0
(-6720 1435);
DISPLAY 0.617021 (-6720 1435);
PAINT ORANGE (-6720 1435);
FORCEPROP 1 LASTPIN (-6725 1625) $PN 1
J 0
(-6720 1587);
DISPLAY 0.617021 (-6720 1587);
PAINT ORANGE (-6720 1587);
FORCEPROP 1 LAST MATERIAL CHIP
J 0
(-6685 1450);
DISPLAY 0.617021 (-6685 1450);
PAINT SKYBLUE (-6685 1450);
FORCEPROP 1 LAST PACK_TYPE 0402
J 0
(-6685 1350);
DISPLAY 0.617021 (-6685 1350);
PAINT SKYBLUE (-6685 1350);
FORCEPROP 1 LAST TOLERANCE 1%
J 0
(-6680 1550);
DISPLAY 0.617021 (-6680 1550);
PAINT SKYBLUE (-6680 1550);
FORCEPROP 1 LAST VALUE 10.0K
J 0
(-6680 1600);
DISPLAY 0.617021 (-6680 1600);
PAINT SKYBLUE (-6680 1600);
FORCEPROP 1 LAST PART_NUMBER G21796-016
J 0
(-6685 1400);
DISPLAY 0.617021 (-6685 1400);
PAINT BLUE (-6685 1400);
FORCEPROP 1 LAST LOCATION R2P15
J 0
(-6680 1650);
DISPLAY 0.617021 (-6680 1650);
PAINT AQUA (-6680 1650);
FORCEPROP 1 LAST WATTAGE 1/16W
J 0
(-6685 1500);
DISPLAY 0.617021 (-6685 1500);
PAINT SKYBLUE (-6685 1500);
FORCEPROP 2 LAST CDS_LIB mstr_discrete
J 0
(-6725 1525);
PAINT ORANGE (-6725 1525);
DISPLAY INVISIBLE (-6725 1525);
FORCEPROP 1 LAST PATH I111
J 0
(-6675 1700);
DISPLAY 0.978723 (-6675 1700);
PAINT WHITE (-6675 1700);
DISPLAY INVISIBLE (-6675 1700);
FORCEPROP 2 LAST SEC 1
J 0
(-6675 1750);
DISPLAY 0.680851 (-6675 1750);
PAINT MONO (-6675 1750);
DISPLAY INVISIBLE (-6675 1750);
FORCEPROP 0 LAST ROOM M_2
J 0
(-6675 1750);
DISPLAY 1.021277 (-6675 1750);
PAINT ORANGE (-6675 1750);
DISPLAY INVISIBLE (-6675 1750);
FORCEPROP 2 LAST SEC_TYPE 0402
J 0
(-6675 1750);
DISPLAY 1.021277 (-6675 1750);
PAINT ORANGE (-6675 1750);
DISPLAY INVISIBLE (-6675 1750);
FORCEPROP 0 LAST BOM_COST ST_FLASH
J 0
(-6675 1850);
DISPLAY 1.021277 (-6675 1850);
PAINT ORANGE (-6675 1850);
DISPLAY INVISIBLE (-6675 1850);
FORCEADD P3V3..1
(-6725 1725);
FORCEPROP 3 LASTPIN (-6725 1675) SIG_NAME P3V3\g
J 0
(-6715 1685);
DISPLAY 0.659574 (-6715 1685);
PAINT MONO (-6715 1685);
DISPLAY INVISIBLE (-6715 1685);
FORCEPROP 1 LAST HDL_POWER P3V3
J 0
(-7050 1600);
DISPLAY 0.872340 (-7050 1600);
PAINT ORANGE (-7050 1600);
DISPLAY INVISIBLE (-7050 1600);
FORCEPROP 1 LAST PATH I112
J 0
(-6680 1727);
DISPLAY 0.340426 (-6680 1727);
PAINT GREEN (-6680 1727);
DISPLAY INVISIBLE (-6680 1727);
FORCEPROP 1 LAST BODY_TYPE PLUMBING
J 0
(-6770 1682);
DISPLAY 0.340426 (-6770 1682);
PAINT GREEN (-6770 1682);
DISPLAY INVISIBLE (-6770 1682);
FORCEPROP 2 LAST CDS_LIB mstr_symbols
J 0
(-6725 1725);
PAINT ORANGE (-6725 1725);
DISPLAY INVISIBLE (-6725 1725);
FORCEPROP 1 LAST SIZE 1B
J 0
(-6680 1747);
DISPLAY 0.340426 (-6680 1747);
PAINT GREEN (-6680 1747);
DISPLAY INVISIBLE (-6680 1747);
FORCEPROP 1 LAST VOLTAGE 3.3V
J 0
(-6770 1682);
DISPLAY 0.340426 (-6770 1682);
PAINT SKYBLUE (-6770 1682);
DISPLAY INVISIBLE (-6770 1682);
FORCEADD RES..2
(-6025 1525);
FORCEPROP 1 LASTPIN (-6025 1425) $PN 2
J 0
(-6020 1435);
DISPLAY 0.617021 (-6020 1435);
PAINT ORANGE (-6020 1435);
FORCEPROP 1 LAST WATTAGE 1/16W
J 0
(-5985 1500);
DISPLAY 0.617021 (-5985 1500);
PAINT SKYBLUE (-5985 1500);
FORCEPROP 1 LAST MATERIAL CHIP
J 0
(-5985 1450);
DISPLAY 0.617021 (-5985 1450);
PAINT SKYBLUE (-5985 1450);
FORCEPROP 1 LAST PART_NUMBER G21796-016
J 0
(-5985 1400);
DISPLAY 0.617021 (-5985 1400);
PAINT BLUE (-5985 1400);
FORCEPROP 1 LASTPIN (-6025 1625) $PN 1
J 0
(-6020 1587);
DISPLAY 0.617021 (-6020 1587);
PAINT ORANGE (-6020 1587);
FORCEPROP 1 LAST TOLERANCE 1%
J 0
(-5980 1550);
DISPLAY 0.617021 (-5980 1550);
PAINT SKYBLUE (-5980 1550);
FORCEPROP 1 LAST VALUE 10.0K
J 0
(-5980 1600);
DISPLAY 0.617021 (-5980 1600);
PAINT SKYBLUE (-5980 1600);
FORCEPROP 1 LAST LOCATION R2P16
J 0
(-5980 1650);
DISPLAY 0.617021 (-5980 1650);
PAINT AQUA (-5980 1650);
FORCEPROP 1 LAST PACK_TYPE 0402
J 0
(-5985 1350);
DISPLAY 0.617021 (-5985 1350);
PAINT SKYBLUE (-5985 1350);
FORCEPROP 2 LAST CDS_LIB mstr_discrete
J 0
(-6025 1525);
PAINT ORANGE (-6025 1525);
DISPLAY INVISIBLE (-6025 1525);
FORCEPROP 2 LAST SEC 1
J 0
(-5975 1750);
DISPLAY 0.680851 (-5975 1750);
PAINT MONO (-5975 1750);
DISPLAY INVISIBLE (-5975 1750);
FORCEPROP 1 LAST PATH I113
J 0
(-5975 1700);
DISPLAY 0.978723 (-5975 1700);
PAINT WHITE (-5975 1700);
DISPLAY INVISIBLE (-5975 1700);
FORCEPROP 0 LAST ROOM M_2
J 0
(-5975 1750);
DISPLAY 1.021277 (-5975 1750);
PAINT ORANGE (-5975 1750);
DISPLAY INVISIBLE (-5975 1750);
FORCEPROP 2 LAST SEC_TYPE 0402
J 0
(-5975 1750);
DISPLAY 1.021277 (-5975 1750);
PAINT ORANGE (-5975 1750);
DISPLAY INVISIBLE (-5975 1750);
FORCEPROP 0 LAST BOM_COST ST_FLASH
J 0
(-5975 1850);
DISPLAY 1.021277 (-5975 1850);
PAINT ORANGE (-5975 1850);
DISPLAY INVISIBLE (-5975 1850);
FORCEADD P3V3_STBY..1
(-6025 1725);
FORCEPROP 3 LASTPIN (-6025 1675) SIG_NAME P3V3_STBY\g
J 0
(-6015 1685);
DISPLAY 0.659574 (-6015 1685);
PAINT MONO (-6015 1685);
DISPLAY INVISIBLE (-6015 1685);
FORCEPROP 1 LAST HDL_POWER P3V3_STBY
J 0
(-6325 1600);
DISPLAY 0.872340 (-6325 1600);
PAINT ORANGE (-6325 1600);
DISPLAY INVISIBLE (-6325 1600);
FORCEPROP 1 LAST VOLTAGE 3.3V
J 0
(-6070 1682);
DISPLAY 0.340426 (-6070 1682);
PAINT SKYBLUE (-6070 1682);
DISPLAY INVISIBLE (-6070 1682);
FORCEPROP 2 LAST CDS_LIB mstr_symbols
J 0
(-6025 1725);
PAINT ORANGE (-6025 1725);
DISPLAY INVISIBLE (-6025 1725);
FORCEPROP 1 LAST BODY_TYPE PLUMBING
J 0
(-6070 1682);
DISPLAY 0.340426 (-6070 1682);
PAINT GREEN (-6070 1682);
DISPLAY INVISIBLE (-6070 1682);
FORCEPROP 1 LAST SIZE 1B
J 0
(-5980 1747);
DISPLAY 0.340426 (-5980 1747);
PAINT GREEN (-5980 1747);
DISPLAY INVISIBLE (-5980 1747);
FORCEPROP 1 LAST PATH I114
J 0
(-5980 1727);
DISPLAY 0.340426 (-5980 1727);
PAINT GREEN (-5980 1727);
DISPLAY INVISIBLE (-5980 1727);
FORCEADD RES..1
(-5650 1250);
FORCEPROP 1 LAST VALUE 0.0
J 2
(-5675 1150);
DISPLAY 0.617021 (-5675 1150);
PAINT SKYBLUE (-5675 1150);
FORCEPROP 1 LAST WATTAGE 1/16W
J 2
(-5675 1100);
DISPLAY 0.617021 (-5675 1100);
PAINT SKYBLUE (-5675 1100);
FORCEPROP 1 LASTPIN (-5750 1250) $PN 1
J 0
(-5738 1262);
DISPLAY 0.617021 (-5738 1262);
PAINT ORANGE (-5738 1262);
FORCEPROP 1 LAST MATERIAL CHIP
J 0
(-5650 1100);
DISPLAY 0.617021 (-5650 1100);
PAINT SKYBLUE (-5650 1100);
FORCEPROP 1 LAST TOLERANCE 5%
J 0
(-5650 1150);
DISPLAY 0.617021 (-5650 1150);
PAINT SKYBLUE (-5650 1150);
FORCEPROP 1 LAST PART_NUMBER G21497-005
J 0
(-5700 1350);
DISPLAY 0.617021 (-5700 1350);
PAINT BLUE (-5700 1350);
FORCEPROP 1 LAST LOCATION R2P14
J 0
(-5700 1300);
DISPLAY 0.617021 (-5700 1300);
PAINT AQUA (-5700 1300);
FORCEPROP 1 LASTPIN (-5550 1250) $PN 2
J 0
(-5588 1262);
DISPLAY 0.617021 (-5588 1262);
PAINT ORANGE (-5588 1262);
FORCEPROP 1 LAST PACK_TYPE 0402
J 0
(-5400 1100);
DISPLAY 0.617021 (-5400 1100);
PAINT SKYBLUE (-5400 1100);
FORCEPROP 2 LAST CDS_LIB mstr_discrete
J 0
(-5650 1250);
PAINT ORANGE (-5650 1250);
DISPLAY INVISIBLE (-5650 1250);
FORCEPROP 2 LAST SEC 1
J 0
(-5700 1450);
DISPLAY 0.680851 (-5700 1450);
PAINT MONO (-5700 1450);
DISPLAY INVISIBLE (-5700 1450);
FORCEPROP 2 LAST SEC_TYPE 0402
J 0
(-5700 1450);
DISPLAY 1.021277 (-5700 1450);
PAINT ORANGE (-5700 1450);
DISPLAY INVISIBLE (-5700 1450);
FORCEPROP 1 LAST PATH I115
J 0
(-5700 1400);
DISPLAY 0.978723 (-5700 1400);
PAINT WHITE (-5700 1400);
DISPLAY INVISIBLE (-5700 1400);
FORCEPROP 0 LAST ROOM M_2
J 0
(-5700 1450);
DISPLAY 1.021277 (-5700 1450);
PAINT ORANGE (-5700 1450);
DISPLAY INVISIBLE (-5700 1450);
FORCEPROP 0 LAST BOM_COST ST_FLASH
J 0
(-5700 1550);
DISPLAY 1.021277 (-5700 1550);
PAINT ORANGE (-5700 1550);
DISPLAY INVISIBLE (-5700 1550);
FORCEADD OFFPAGE..2
(-4950 1250);
FORCEPROP 2 LAST $XR0 120 
J 0
(-4761 1250);
DISPLAY 0.638298 (-4761 1250);
PAINT MONO (-4761 1250);
FORCEPROP 2 LAST $XR1 145 
J 0
(-4761 1250);
DISPLAY 0.638298 (-4761 1250);
PAINT MONO (-4761 1250);
FORCEPROP 1 LAST COMMENT_BODY TRUE
J 0
(-4995 1155);
DISPLAY 0.872340 (-4995 1155);
PAINT GREEN (-4995 1155);
DISPLAY INVISIBLE (-4995 1155);
FORCEPROP 2 LAST CDS_LIB mstr_standard
J 0
(-4950 1250);
PAINT ORANGE (-4950 1250);
DISPLAY INVISIBLE (-4950 1250);
FORCEPROP 2 LAST PATH I116
J 0
(-4775 1325);
DISPLAY 1.021277 (-4775 1325);
PAINT ORANGE (-4775 1325);
DISPLAY INVISIBLE (-4775 1325);
FORCEPROP 1 LAST OFFPAGE TRUE
J 0
(-4625 1125);
DISPLAY 0.872340 (-4625 1125);
PAINT GREEN (-4625 1125);
DISPLAY INVISIBLE (-4625 1125);
FORCEADD CAP_A..1
(-6425 700);
FORCEPROP 1 LAST PACK_TYPE 0402V
J 0
(-6375 500);
DISPLAY 0.617021 (-6375 500);
PAINT SKYBLUE (-6375 500);
FORCEPROP 1 LASTPIN (-6425 800) $PN 1
J 0
(-6415 780);
DISPLAY 0.617021 (-6415 780);
PAINT ORANGE (-6415 780);
FORCEPROP 1 LASTPIN (-6425 600) $PN 2
J 0
(-6415 580);
DISPLAY 0.617021 (-6415 580);
PAINT ORANGE (-6415 580);
FORCEPROP 1 LAST MATERIAL X7R
J 0
(-6375 600);
DISPLAY 0.617021 (-6375 600);
PAINT SKYBLUE (-6375 600);
FORCEPROP 1 LAST TOLERANCE 10%
J 0
(-6375 650);
DISPLAY 0.617021 (-6375 650);
PAINT SKYBLUE (-6375 650);
FORCEPROP 1 LAST VALUE 0.1UF
J 0
(-6375 750);
DISPLAY 0.617021 (-6375 750);
PAINT SKYBLUE (-6375 750);
FORCEPROP 1 LAST LOCATION C2P9
J 0
(-6375 800);
DISPLAY 0.617021 (-6375 800);
PAINT AQUA (-6375 800);
FORCEPROP 1 LAST PART_NUMBER A36096-030
J 0
(-6375 550);
DISPLAY 0.617021 (-6375 550);
PAINT BLUE (-6375 550);
FORCEPROP 1 LAST VOLTAGE 16V
J 0
(-6375 700);
DISPLAY 0.617021 (-6375 700);
PAINT SKYBLUE (-6375 700);
FORCEPROP 2 LAST CDS_LIB dev_discrete
J 0
(-6425 700);
PAINT ORANGE (-6425 700);
DISPLAY INVISIBLE (-6425 700);
FORCEPROP 2 LAST SEC_TYPE 0402V
J 0
(-6375 900);
DISPLAY 1.021277 (-6375 900);
PAINT ORANGE (-6375 900);
DISPLAY INVISIBLE (-6375 900);
FORCEPROP 2 LAST SEC 1
J 0
(-6375 900);
DISPLAY 0.680851 (-6375 900);
PAINT MONO (-6375 900);
DISPLAY INVISIBLE (-6375 900);
FORCEPROP 2 LAST CDS_SEC 1
J 0
(-6375 850);
PAINT ORANGE (-6375 850);
DISPLAY INVISIBLE (-6375 850);
FORCEPROP 0 LAST ROOM M_2
J 0
(-6375 900);
DISPLAY 1.021277 (-6375 900);
PAINT ORANGE (-6375 900);
DISPLAY INVISIBLE (-6375 900);
FORCEPROP 1 LAST PATH I117
J 0
(-6375 850);
DISPLAY 0.978723 (-6375 850);
PAINT WHITE (-6375 850);
DISPLAY INVISIBLE (-6375 850);
FORCEPROP 0 LAST BOM_COST SD_FLASH
J 0
(-6375 1000);
DISPLAY 1.021277 (-6375 1000);
PAINT ORANGE (-6375 1000);
DISPLAY INVISIBLE (-6375 1000);
FORCEADD P3V3_STBY..1
(-6425 925);
FORCEPROP 3 LASTPIN (-6425 875) SIG_NAME P3V3_STBY\g
J 0
(-6415 885);
DISPLAY 0.659574 (-6415 885);
PAINT MONO (-6415 885);
DISPLAY INVISIBLE (-6415 885);
FORCEPROP 1 LAST HDL_POWER P3V3_STBY
J 0
(-6725 800);
DISPLAY 0.872340 (-6725 800);
PAINT ORANGE (-6725 800);
DISPLAY INVISIBLE (-6725 800);
FORCEPROP 1 LAST VOLTAGE 3.3V
J 0
(-6470 882);
DISPLAY 0.340426 (-6470 882);
PAINT SKYBLUE (-6470 882);
DISPLAY INVISIBLE (-6470 882);
FORCEPROP 2 LAST CDS_LIB mstr_symbols
J 0
(-6425 925);
PAINT ORANGE (-6425 925);
DISPLAY INVISIBLE (-6425 925);
FORCEPROP 1 LAST BODY_TYPE PLUMBING
J 0
(-6470 882);
DISPLAY 0.340426 (-6470 882);
PAINT GREEN (-6470 882);
DISPLAY INVISIBLE (-6470 882);
FORCEPROP 1 LAST PATH I118
J 0
(-6380 927);
DISPLAY 0.340426 (-6380 927);
PAINT GREEN (-6380 927);
DISPLAY INVISIBLE (-6380 927);
FORCEPROP 1 LAST SIZE 1B
J 0
(-6380 947);
DISPLAY 0.340426 (-6380 947);
PAINT GREEN (-6380 947);
DISPLAY INVISIBLE (-6380 947);
FORCEADD GND..1
(-6425 475);
FORCEPROP 3 LASTPIN (-6425 525) SIG_NAME GND\g
J 0
(-6415 535);
DISPLAY 0.659574 (-6415 535);
PAINT MONO (-6415 535);
DISPLAY INVISIBLE (-6415 535);
FORCEPROP 1 LAST PATH I119
J 0
(-6350 475);
DISPLAY 0.872340 (-6350 475);
PAINT AQUA (-6350 475);
DISPLAY INVISIBLE (-6350 475);
FORCEPROP 1 LAST BODY_TYPE PLUMBING
J 0
(-6470 432);
DISPLAY 0.340426 (-6470 432);
PAINT GREEN (-6470 432);
DISPLAY INVISIBLE (-6470 432);
FORCEPROP 1 LAST SIZE 1B
J 0
(-6350 425);
DISPLAY 0.872340 (-6350 425);
PAINT AQUA (-6350 425);
DISPLAY INVISIBLE (-6350 425);
FORCEPROP 1 LAST VOLTAGE 0.0V
J 0
(-6470 432);
DISPLAY 0.340426 (-6470 432);
PAINT SKYBLUE (-6470 432);
DISPLAY INVISIBLE (-6470 432);
FORCEPROP 2 LAST CDS_LIB mstr_symbols
J 0
(-6425 475);
PAINT ORANGE (-6425 475);
DISPLAY INVISIBLE (-6425 475);
FORCEPROP 1 LAST HDL_POWER GND
J 0
(-6425 625);
DISPLAY 0.872340 (-6425 625);
PAINT GREEN (-6425 625);
DISPLAY INVISIBLE (-6425 625);
FORCEADD CAP_A..1
(-1650 4500);
FORCEPROP 1 LAST PART_NUMBER A36096-030
J 0
(-1600 4350);
DISPLAY 0.617021 (-1600 4350);
PAINT BLUE (-1600 4350);
FORCEPROP 1 LAST LOCATION C2T29
J 0
(-1600 4600);
DISPLAY 0.617021 (-1600 4600);
PAINT AQUA (-1600 4600);
FORCEPROP 1 LAST VALUE 0.1UF
J 0
(-1600 4550);
DISPLAY 0.617021 (-1600 4550);
PAINT SKYBLUE (-1600 4550);
FORCEPROP 1 LAST TOLERANCE 10%
J 0
(-1600 4450);
DISPLAY 0.617021 (-1600 4450);
PAINT SKYBLUE (-1600 4450);
FORCEPROP 1 LAST PACK_TYPE 0402V
J 0
(-1600 4300);
DISPLAY 0.617021 (-1600 4300);
PAINT SKYBLUE (-1600 4300);
FORCEPROP 1 LAST VOLTAGE 16V
J 0
(-1600 4500);
DISPLAY 0.617021 (-1600 4500);
PAINT SKYBLUE (-1600 4500);
FORCEPROP 1 LAST MATERIAL X7R
J 0
(-1600 4400);
DISPLAY 0.617021 (-1600 4400);
PAINT SKYBLUE (-1600 4400);
FORCEPROP 1 LASTPIN (-1650 4400) $PN 2
J 0
(-1640 4380);
DISPLAY 0.617021 (-1640 4380);
PAINT ORANGE (-1640 4380);
FORCEPROP 1 LASTPIN (-1650 4600) $PN 1
J 0
(-1640 4580);
DISPLAY 0.617021 (-1640 4580);
PAINT ORANGE (-1640 4580);
FORCEPROP 0 LAST BOM_COST SD_FLASH
J 0
(-1600 4800);
DISPLAY 1.021277 (-1600 4800);
PAINT ORANGE (-1600 4800);
DISPLAY INVISIBLE (-1600 4800);
FORCEPROP 2 LAST SEC_TYPE 0402V
J 0
(-1600 4700);
DISPLAY 1.021277 (-1600 4700);
PAINT ORANGE (-1600 4700);
DISPLAY INVISIBLE (-1600 4700);
FORCEPROP 0 LAST ROOM M_2
J 0
(-1600 4700);
DISPLAY 1.021277 (-1600 4700);
PAINT ORANGE (-1600 4700);
DISPLAY INVISIBLE (-1600 4700);
FORCEPROP 1 LAST PATH I120
J 0
(-1600 4650);
DISPLAY 0.978723 (-1600 4650);
PAINT WHITE (-1600 4650);
DISPLAY INVISIBLE (-1600 4650);
FORCEPROP 2 LAST CDS_SEC 1
J 0
(-1600 4650);
PAINT ORANGE (-1600 4650);
DISPLAY INVISIBLE (-1600 4650);
FORCEPROP 2 LAST SEC 1
J 0
(-1600 4700);
DISPLAY 0.680851 (-1600 4700);
PAINT MONO (-1600 4700);
DISPLAY INVISIBLE (-1600 4700);
FORCEPROP 2 LAST CDS_LOCATION C2T29
J 0
(-1600 4600);
DISPLAY 0.617021 (-1600 4600);
PAINT AQUA (-1600 4600);
DISPLAY INVISIBLE (-1600 4600);
FORCEPROP 2 LAST CDS_LIB dev_discrete
J 0
(-1650 4500);
PAINT ORANGE (-1650 4500);
DISPLAY INVISIBLE (-1650 4500);
FORCEADD GND..1
(-1650 4275);
FORCEPROP 3 LASTPIN (-1650 4325) SIG_NAME GND\g
J 0
(-1640 4335);
DISPLAY 0.659574 (-1640 4335);
PAINT MONO (-1640 4335);
DISPLAY INVISIBLE (-1640 4335);
FORCEPROP 1 LAST PATH I122
J 0
(-1575 4275);
DISPLAY 0.872340 (-1575 4275);
PAINT AQUA (-1575 4275);
DISPLAY INVISIBLE (-1575 4275);
FORCEPROP 1 LAST SIZE 1B
J 0
(-1575 4225);
DISPLAY 0.872340 (-1575 4225);
PAINT AQUA (-1575 4225);
DISPLAY INVISIBLE (-1575 4225);
FORCEPROP 1 LAST HDL_POWER GND
J 0
(-1650 4425);
DISPLAY 0.872340 (-1650 4425);
PAINT GREEN (-1650 4425);
DISPLAY INVISIBLE (-1650 4425);
FORCEPROP 1 LAST VOLTAGE 0.0V
J 0
(-1695 4232);
DISPLAY 0.340426 (-1695 4232);
PAINT SKYBLUE (-1695 4232);
DISPLAY INVISIBLE (-1695 4232);
FORCEPROP 2 LAST CDS_LIB mstr_symbols
J 0
(-1650 4275);
PAINT MONO (-1650 4275);
DISPLAY INVISIBLE (-1650 4275);
FORCEPROP 1 LAST BODY_TYPE PLUMBING
J 0
(-1695 4232);
DISPLAY 0.340426 (-1695 4232);
PAINT GREEN (-1695 4232);
DISPLAY INVISIBLE (-1695 4232);
FORCEADD CAP_A..1
(-1400 4500);
FORCEPROP 1 LAST PART_NUMBER A36096-030
J 0
(-1350 4350);
DISPLAY 0.617021 (-1350 4350);
PAINT BLUE (-1350 4350);
FORCEPROP 1 LAST TOLERANCE 10%
J 0
(-1350 4450);
DISPLAY 0.617021 (-1350 4450);
PAINT SKYBLUE (-1350 4450);
FORCEPROP 1 LAST PACK_TYPE 0402V
J 0
(-1350 4300);
DISPLAY 0.617021 (-1350 4300);
PAINT SKYBLUE (-1350 4300);
FORCEPROP 1 LAST VOLTAGE 16V
J 0
(-1350 4500);
DISPLAY 0.617021 (-1350 4500);
PAINT SKYBLUE (-1350 4500);
FORCEPROP 1 LAST MATERIAL X7R
J 0
(-1350 4400);
DISPLAY 0.617021 (-1350 4400);
PAINT SKYBLUE (-1350 4400);
FORCEPROP 1 LASTPIN (-1400 4600) $PN 1
J 0
(-1390 4580);
DISPLAY 0.617021 (-1390 4580);
PAINT ORANGE (-1390 4580);
FORCEPROP 1 LASTPIN (-1400 4400) $PN 2
J 0
(-1390 4380);
DISPLAY 0.617021 (-1390 4380);
PAINT ORANGE (-1390 4380);
FORCEPROP 1 LAST LOCATION C2T26
J 0
(-1350 4600);
DISPLAY 0.617021 (-1350 4600);
PAINT AQUA (-1350 4600);
FORCEPROP 1 LAST VALUE 0.1UF
J 0
(-1350 4550);
DISPLAY 0.617021 (-1350 4550);
PAINT SKYBLUE (-1350 4550);
FORCEPROP 2 LAST SEC_TYPE 0402V
J 0
(-1350 4700);
DISPLAY 1.021277 (-1350 4700);
PAINT ORANGE (-1350 4700);
DISPLAY INVISIBLE (-1350 4700);
FORCEPROP 2 LAST SEC 1
J 0
(-1350 4700);
DISPLAY 0.680851 (-1350 4700);
PAINT MONO (-1350 4700);
DISPLAY INVISIBLE (-1350 4700);
FORCEPROP 2 LAST CDS_SEC 1
J 0
(-1350 4650);
PAINT ORANGE (-1350 4650);
DISPLAY INVISIBLE (-1350 4650);
FORCEPROP 0 LAST BOM_COST SD_FLASH
J 0
(-1350 4800);
DISPLAY 1.021277 (-1350 4800);
PAINT ORANGE (-1350 4800);
DISPLAY INVISIBLE (-1350 4800);
FORCEPROP 0 LAST ROOM M_2
J 0
(-1350 4700);
DISPLAY 1.021277 (-1350 4700);
PAINT ORANGE (-1350 4700);
DISPLAY INVISIBLE (-1350 4700);
FORCEPROP 1 LAST PATH I123
J 0
(-1350 4650);
DISPLAY 0.978723 (-1350 4650);
PAINT WHITE (-1350 4650);
DISPLAY INVISIBLE (-1350 4650);
FORCEPROP 2 LAST CDS_LOCATION C2T26
J 0
(-1350 4600);
DISPLAY 0.617021 (-1350 4600);
PAINT AQUA (-1350 4600);
DISPLAY INVISIBLE (-1350 4600);
FORCEPROP 2 LAST CDS_LIB dev_discrete
J 0
(-1400 4500);
PAINT ORANGE (-1400 4500);
DISPLAY INVISIBLE (-1400 4500);
FORCEADD CAP_A..1
(-1150 4500);
FORCEPROP 1 LAST LOCATION C2T21
J 0
(-1100 4600);
DISPLAY 0.617021 (-1100 4600);
PAINT AQUA (-1100 4600);
FORCEPROP 1 LAST VOLTAGE 16V
J 0
(-1100 4500);
DISPLAY 0.617021 (-1100 4500);
PAINT SKYBLUE (-1100 4500);
FORCEPROP 1 LAST PACK_TYPE 0402V
J 0
(-1100 4300);
DISPLAY 0.617021 (-1100 4300);
PAINT SKYBLUE (-1100 4300);
FORCEPROP 1 LAST TOLERANCE 10%
J 0
(-1100 4450);
DISPLAY 0.617021 (-1100 4450);
PAINT SKYBLUE (-1100 4450);
FORCEPROP 1 LAST VALUE 0.1UF
J 0
(-1100 4550);
DISPLAY 0.617021 (-1100 4550);
PAINT SKYBLUE (-1100 4550);
FORCEPROP 1 LASTPIN (-1150 4400) $PN 2
J 0
(-1140 4380);
DISPLAY 0.617021 (-1140 4380);
PAINT ORANGE (-1140 4380);
FORCEPROP 1 LASTPIN (-1150 4600) $PN 1
J 0
(-1140 4580);
DISPLAY 0.617021 (-1140 4580);
PAINT ORANGE (-1140 4580);
FORCEPROP 1 LAST MATERIAL X7R
J 0
(-1100 4400);
DISPLAY 0.617021 (-1100 4400);
PAINT SKYBLUE (-1100 4400);
FORCEPROP 1 LAST PART_NUMBER A36096-030
J 0
(-1100 4350);
DISPLAY 0.617021 (-1100 4350);
PAINT BLUE (-1100 4350);
FORCEPROP 2 LAST SEC_TYPE 0402V
J 0
(-1100 4700);
DISPLAY 1.021277 (-1100 4700);
PAINT ORANGE (-1100 4700);
DISPLAY INVISIBLE (-1100 4700);
FORCEPROP 2 LAST SEC 1
J 0
(-1100 4700);
DISPLAY 0.680851 (-1100 4700);
PAINT MONO (-1100 4700);
DISPLAY INVISIBLE (-1100 4700);
FORCEPROP 2 LAST CDS_SEC 1
J 0
(-1100 4650);
PAINT ORANGE (-1100 4650);
DISPLAY INVISIBLE (-1100 4650);
FORCEPROP 0 LAST BOM_COST SD_FLASH
J 0
(-1100 4800);
DISPLAY 1.021277 (-1100 4800);
PAINT ORANGE (-1100 4800);
DISPLAY INVISIBLE (-1100 4800);
FORCEPROP 0 LAST ROOM M_2
J 0
(-1100 4700);
DISPLAY 1.021277 (-1100 4700);
PAINT ORANGE (-1100 4700);
DISPLAY INVISIBLE (-1100 4700);
FORCEPROP 1 LAST PATH I124
J 0
(-1100 4650);
DISPLAY 0.978723 (-1100 4650);
PAINT WHITE (-1100 4650);
DISPLAY INVISIBLE (-1100 4650);
FORCEPROP 2 LAST CDS_LOCATION C2T21
J 0
(-1100 4600);
DISPLAY 0.617021 (-1100 4600);
PAINT AQUA (-1100 4600);
DISPLAY INVISIBLE (-1100 4600);
FORCEPROP 2 LAST CDS_LIB dev_discrete
J 0
(-1150 4500);
PAINT ORANGE (-1150 4500);
DISPLAY INVISIBLE (-1150 4500);
FORCEADD P3V3..1
(-1650 4725);
FORCEPROP 3 LASTPIN (-1650 4675) SIG_NAME P3V3\g
J 0
(-1640 4685);
DISPLAY 0.659574 (-1640 4685);
PAINT MONO (-1640 4685);
DISPLAY INVISIBLE (-1640 4685);
FORCEPROP 1 LAST SIZE 1B
J 0
(-1605 4747);
DISPLAY 0.340426 (-1605 4747);
PAINT GREEN (-1605 4747);
DISPLAY INVISIBLE (-1605 4747);
FORCEPROP 1 LAST PATH I125
J 0
(-1605 4727);
DISPLAY 0.340426 (-1605 4727);
PAINT GREEN (-1605 4727);
DISPLAY INVISIBLE (-1605 4727);
FORCEPROP 2 LAST CDS_LIB mstr_symbols
J 0
(-1650 4725);
PAINT MONO (-1650 4725);
DISPLAY INVISIBLE (-1650 4725);
FORCEPROP 1 LAST VOLTAGE 3.3V
J 0
(-1695 4682);
DISPLAY 0.340426 (-1695 4682);
PAINT SKYBLUE (-1695 4682);
DISPLAY INVISIBLE (-1695 4682);
FORCEPROP 1 LAST BODY_TYPE PLUMBING
J 0
(-1695 4682);
DISPLAY 0.340426 (-1695 4682);
PAINT GREEN (-1695 4682);
DISPLAY INVISIBLE (-1695 4682);
FORCEPROP 1 LAST HDL_POWER P3V3
J 0
(-1975 4600);
DISPLAY 0.872340 (-1975 4600);
PAINT ORANGE (-1975 4600);
DISPLAY INVISIBLE (-1975 4600);
FORCEADD CAP_A..1
(-1150 3650);
FORCEPROP 1 LAST PART_NUMBER A36096-030
J 0
(-1100 3500);
DISPLAY 0.617021 (-1100 3500);
PAINT BLUE (-1100 3500);
FORCEPROP 1 LAST LOCATION C2T16
J 0
(-1100 3750);
DISPLAY 0.617021 (-1100 3750);
PAINT AQUA (-1100 3750);
FORCEPROP 1 LAST VOLTAGE 16V
J 0
(-1100 3650);
DISPLAY 0.617021 (-1100 3650);
PAINT SKYBLUE (-1100 3650);
FORCEPROP 1 LAST VALUE 0.1UF
J 0
(-1100 3700);
DISPLAY 0.617021 (-1100 3700);
PAINT SKYBLUE (-1100 3700);
FORCEPROP 1 LAST TOLERANCE 10%
J 0
(-1100 3600);
DISPLAY 0.617021 (-1100 3600);
PAINT SKYBLUE (-1100 3600);
FORCEPROP 1 LASTPIN (-1150 3750) $PN 1
J 0
(-1140 3730);
DISPLAY 0.617021 (-1140 3730);
PAINT ORANGE (-1140 3730);
FORCEPROP 1 LAST PACK_TYPE 0402V
J 0
(-1100 3450);
DISPLAY 0.617021 (-1100 3450);
PAINT SKYBLUE (-1100 3450);
FORCEPROP 1 LAST MATERIAL X7R
J 0
(-1100 3550);
DISPLAY 0.617021 (-1100 3550);
PAINT SKYBLUE (-1100 3550);
FORCEPROP 1 LASTPIN (-1150 3550) $PN 2
J 0
(-1140 3530);
DISPLAY 0.617021 (-1140 3530);
PAINT ORANGE (-1140 3530);
FORCEPROP 0 LAST BOM_COST SD_FLASH
J 0
(-1100 3950);
DISPLAY 1.021277 (-1100 3950);
PAINT ORANGE (-1100 3950);
DISPLAY INVISIBLE (-1100 3950);
FORCEPROP 0 LAST ROOM M_2
J 0
(-1100 3850);
DISPLAY 1.021277 (-1100 3850);
PAINT ORANGE (-1100 3850);
DISPLAY INVISIBLE (-1100 3850);
FORCEPROP 2 LAST SEC 1
J 0
(-1100 3850);
DISPLAY 0.680851 (-1100 3850);
PAINT MONO (-1100 3850);
DISPLAY INVISIBLE (-1100 3850);
FORCEPROP 2 LAST SEC_TYPE 0402V
J 0
(-1100 3850);
DISPLAY 1.021277 (-1100 3850);
PAINT ORANGE (-1100 3850);
DISPLAY INVISIBLE (-1100 3850);
FORCEPROP 2 LAST CDS_SEC 1
J 0
(-1100 3800);
PAINT ORANGE (-1100 3800);
DISPLAY INVISIBLE (-1100 3800);
FORCEPROP 1 LAST PATH I126
J 0
(-1100 3800);
DISPLAY 0.978723 (-1100 3800);
PAINT WHITE (-1100 3800);
DISPLAY INVISIBLE (-1100 3800);
FORCEPROP 2 LAST CDS_LOCATION C2T16
J 0
(-1100 3750);
DISPLAY 0.617021 (-1100 3750);
PAINT AQUA (-1100 3750);
DISPLAY INVISIBLE (-1100 3750);
FORCEPROP 2 LAST CDS_LIB dev_discrete
J 0
(-1150 3650);
PAINT ORANGE (-1150 3650);
DISPLAY INVISIBLE (-1150 3650);
FORCEADD CAP_A..1
(-1400 3650);
FORCEPROP 1 LAST LOCATION C2T15
J 0
(-1350 3750);
DISPLAY 0.617021 (-1350 3750);
PAINT AQUA (-1350 3750);
FORCEPROP 1 LAST PART_NUMBER A36096-030
J 0
(-1350 3500);
DISPLAY 0.617021 (-1350 3500);
PAINT BLUE (-1350 3500);
FORCEPROP 1 LAST VALUE 0.1UF
J 0
(-1350 3700);
DISPLAY 0.617021 (-1350 3700);
PAINT SKYBLUE (-1350 3700);
FORCEPROP 1 LAST TOLERANCE 10%
J 0
(-1350 3600);
DISPLAY 0.617021 (-1350 3600);
PAINT SKYBLUE (-1350 3600);
FORCEPROP 1 LAST PACK_TYPE 0402V
J 0
(-1350 3450);
DISPLAY 0.617021 (-1350 3450);
PAINT SKYBLUE (-1350 3450);
FORCEPROP 1 LAST VOLTAGE 16V
J 0
(-1350 3650);
DISPLAY 0.617021 (-1350 3650);
PAINT SKYBLUE (-1350 3650);
FORCEPROP 1 LAST MATERIAL X7R
J 0
(-1350 3550);
DISPLAY 0.617021 (-1350 3550);
PAINT SKYBLUE (-1350 3550);
FORCEPROP 1 LASTPIN (-1400 3750) $PN 1
J 0
(-1390 3730);
DISPLAY 0.617021 (-1390 3730);
PAINT ORANGE (-1390 3730);
FORCEPROP 1 LASTPIN (-1400 3550) $PN 2
J 0
(-1390 3530);
DISPLAY 0.617021 (-1390 3530);
PAINT ORANGE (-1390 3530);
FORCEPROP 2 LAST SEC_TYPE 0402V
J 0
(-1350 3850);
DISPLAY 1.021277 (-1350 3850);
PAINT ORANGE (-1350 3850);
DISPLAY INVISIBLE (-1350 3850);
FORCEPROP 2 LAST SEC 1
J 0
(-1350 3850);
DISPLAY 0.680851 (-1350 3850);
PAINT MONO (-1350 3850);
DISPLAY INVISIBLE (-1350 3850);
FORCEPROP 0 LAST BOM_COST SD_FLASH
J 0
(-1350 3950);
DISPLAY 1.021277 (-1350 3950);
PAINT ORANGE (-1350 3950);
DISPLAY INVISIBLE (-1350 3950);
FORCEPROP 0 LAST ROOM M_2
J 0
(-1350 3850);
DISPLAY 1.021277 (-1350 3850);
PAINT ORANGE (-1350 3850);
DISPLAY INVISIBLE (-1350 3850);
FORCEPROP 2 LAST CDS_SEC 1
J 0
(-1350 3800);
PAINT ORANGE (-1350 3800);
DISPLAY INVISIBLE (-1350 3800);
FORCEPROP 1 LAST PATH I127
J 0
(-1350 3800);
DISPLAY 0.978723 (-1350 3800);
PAINT WHITE (-1350 3800);
DISPLAY INVISIBLE (-1350 3800);
FORCEPROP 2 LAST CDS_LOCATION C2T15
J 0
(-1350 3750);
DISPLAY 0.617021 (-1350 3750);
PAINT AQUA (-1350 3750);
DISPLAY INVISIBLE (-1350 3750);
FORCEPROP 2 LAST CDS_LIB dev_discrete
J 0
(-1400 3650);
PAINT ORANGE (-1400 3650);
DISPLAY INVISIBLE (-1400 3650);
FORCEADD P3V3..1
(-1650 3875);
FORCEPROP 3 LASTPIN (-1650 3825) SIG_NAME P3V3\g
J 0
(-1640 3835);
DISPLAY 0.659574 (-1640 3835);
PAINT MONO (-1640 3835);
DISPLAY INVISIBLE (-1640 3835);
FORCEPROP 2 LAST CDS_LIB mstr_symbols
J 0
(-1650 3875);
PAINT MONO (-1650 3875);
DISPLAY INVISIBLE (-1650 3875);
FORCEPROP 1 LAST SIZE 1B
J 0
(-1605 3897);
DISPLAY 0.340426 (-1605 3897);
PAINT GREEN (-1605 3897);
DISPLAY INVISIBLE (-1605 3897);
FORCEPROP 1 LAST PATH I128
J 0
(-1605 3877);
DISPLAY 0.340426 (-1605 3877);
PAINT GREEN (-1605 3877);
DISPLAY INVISIBLE (-1605 3877);
FORCEPROP 1 LAST VOLTAGE 3.3V
J 0
(-1695 3832);
DISPLAY 0.340426 (-1695 3832);
PAINT SKYBLUE (-1695 3832);
DISPLAY INVISIBLE (-1695 3832);
FORCEPROP 1 LAST BODY_TYPE PLUMBING
J 0
(-1695 3832);
DISPLAY 0.340426 (-1695 3832);
PAINT GREEN (-1695 3832);
DISPLAY INVISIBLE (-1695 3832);
FORCEPROP 1 LAST HDL_POWER P3V3
J 0
(-1975 3750);
DISPLAY 0.872340 (-1975 3750);
PAINT ORANGE (-1975 3750);
DISPLAY INVISIBLE (-1975 3750);
FORCEADD CAP_A..1
(-1650 3650);
FORCEPROP 1 LAST PART_NUMBER A36096-030
J 0
(-1600 3500);
DISPLAY 0.617021 (-1600 3500);
PAINT BLUE (-1600 3500);
FORCEPROP 1 LAST LOCATION C2T24
J 0
(-1600 3750);
DISPLAY 0.617021 (-1600 3750);
PAINT AQUA (-1600 3750);
FORCEPROP 1 LAST VALUE 0.1UF
J 0
(-1600 3700);
DISPLAY 0.617021 (-1600 3700);
PAINT SKYBLUE (-1600 3700);
FORCEPROP 1 LAST TOLERANCE 10%
J 0
(-1600 3600);
DISPLAY 0.617021 (-1600 3600);
PAINT SKYBLUE (-1600 3600);
FORCEPROP 1 LAST VOLTAGE 16V
J 0
(-1600 3650);
DISPLAY 0.617021 (-1600 3650);
PAINT SKYBLUE (-1600 3650);
FORCEPROP 1 LASTPIN (-1650 3750) $PN 1
J 0
(-1640 3730);
DISPLAY 0.617021 (-1640 3730);
PAINT ORANGE (-1640 3730);
FORCEPROP 1 LAST PACK_TYPE 0402V
J 0
(-1600 3450);
DISPLAY 0.617021 (-1600 3450);
PAINT SKYBLUE (-1600 3450);
FORCEPROP 1 LAST MATERIAL X7R
J 0
(-1600 3550);
DISPLAY 0.617021 (-1600 3550);
PAINT SKYBLUE (-1600 3550);
FORCEPROP 1 LASTPIN (-1650 3550) $PN 2
J 0
(-1640 3530);
DISPLAY 0.617021 (-1640 3530);
PAINT ORANGE (-1640 3530);
FORCEPROP 2 LAST SEC_TYPE 0402V
J 0
(-1600 3850);
DISPLAY 1.021277 (-1600 3850);
PAINT ORANGE (-1600 3850);
DISPLAY INVISIBLE (-1600 3850);
FORCEPROP 2 LAST SEC 1
J 0
(-1600 3850);
DISPLAY 0.680851 (-1600 3850);
PAINT MONO (-1600 3850);
DISPLAY INVISIBLE (-1600 3850);
FORCEPROP 0 LAST ROOM M_2
J 0
(-1600 3850);
DISPLAY 1.021277 (-1600 3850);
PAINT ORANGE (-1600 3850);
DISPLAY INVISIBLE (-1600 3850);
FORCEPROP 0 LAST BOM_COST SD_FLASH
J 0
(-1600 3950);
DISPLAY 1.021277 (-1600 3950);
PAINT ORANGE (-1600 3950);
DISPLAY INVISIBLE (-1600 3950);
FORCEPROP 1 LAST PATH I129
J 0
(-1600 3800);
DISPLAY 0.978723 (-1600 3800);
PAINT WHITE (-1600 3800);
DISPLAY INVISIBLE (-1600 3800);
FORCEPROP 2 LAST CDS_SEC 1
J 0
(-1600 3800);
PAINT ORANGE (-1600 3800);
DISPLAY INVISIBLE (-1600 3800);
FORCEPROP 2 LAST CDS_LOCATION C2T24
J 0
(-1600 3750);
DISPLAY 0.617021 (-1600 3750);
PAINT AQUA (-1600 3750);
DISPLAY INVISIBLE (-1600 3750);
FORCEPROP 2 LAST CDS_LIB dev_discrete
J 0
(-1650 3650);
PAINT ORANGE (-1650 3650);
DISPLAY INVISIBLE (-1650 3650);
FORCEADD GND..1
(-1650 3425);
FORCEPROP 3 LASTPIN (-1650 3475) SIG_NAME GND\g
J 0
(-1640 3485);
DISPLAY 0.659574 (-1640 3485);
PAINT MONO (-1640 3485);
DISPLAY INVISIBLE (-1640 3485);
FORCEPROP 1 LAST HDL_POWER GND
J 0
(-1650 3575);
DISPLAY 0.872340 (-1650 3575);
PAINT GREEN (-1650 3575);
DISPLAY INVISIBLE (-1650 3575);
FORCEPROP 1 LAST PATH I130
J 0
(-1575 3425);
DISPLAY 0.872340 (-1575 3425);
PAINT AQUA (-1575 3425);
DISPLAY INVISIBLE (-1575 3425);
FORCEPROP 1 LAST SIZE 1B
J 0
(-1575 3375);
DISPLAY 0.872340 (-1575 3375);
PAINT AQUA (-1575 3375);
DISPLAY INVISIBLE (-1575 3375);
FORCEPROP 2 LAST CDS_LIB mstr_symbols
J 0
(-1650 3425);
PAINT MONO (-1650 3425);
DISPLAY INVISIBLE (-1650 3425);
FORCEPROP 1 LAST BODY_TYPE PLUMBING
J 0
(-1695 3382);
DISPLAY 0.340426 (-1695 3382);
PAINT GREEN (-1695 3382);
DISPLAY INVISIBLE (-1695 3382);
FORCEPROP 1 LAST VOLTAGE 0.0V
J 0
(-1695 3382);
DISPLAY 0.340426 (-1695 3382);
PAINT SKYBLUE (-1695 3382);
DISPLAY INVISIBLE (-1695 3382);
FORCEADD CAP_A..1
(-1150 2800);
FORCEPROP 1 LAST PART_NUMBER A36096-030
J 0
(-1100 2650);
DISPLAY 0.617021 (-1100 2650);
PAINT BLUE (-1100 2650);
FORCEPROP 1 LAST LOCATION C2T2
J 0
(-1100 2900);
DISPLAY 0.617021 (-1100 2900);
PAINT AQUA (-1100 2900);
FORCEPROP 1 LAST VALUE 0.1UF
J 0
(-1100 2850);
DISPLAY 0.617021 (-1100 2850);
PAINT SKYBLUE (-1100 2850);
FORCEPROP 1 LAST TOLERANCE 10%
J 0
(-1100 2750);
DISPLAY 0.617021 (-1100 2750);
PAINT SKYBLUE (-1100 2750);
FORCEPROP 1 LAST PACK_TYPE 0402V
J 0
(-1100 2600);
DISPLAY 0.617021 (-1100 2600);
PAINT SKYBLUE (-1100 2600);
FORCEPROP 1 LAST VOLTAGE 16V
J 0
(-1100 2800);
DISPLAY 0.617021 (-1100 2800);
PAINT SKYBLUE (-1100 2800);
FORCEPROP 1 LAST MATERIAL X7R
J 0
(-1100 2700);
DISPLAY 0.617021 (-1100 2700);
PAINT SKYBLUE (-1100 2700);
FORCEPROP 1 LASTPIN (-1150 2900) $PN 1
J 0
(-1140 2880);
DISPLAY 0.617021 (-1140 2880);
PAINT ORANGE (-1140 2880);
FORCEPROP 1 LASTPIN (-1150 2700) $PN 2
J 0
(-1140 2680);
DISPLAY 0.617021 (-1140 2680);
PAINT ORANGE (-1140 2680);
FORCEPROP 0 LAST BOM_COST SD_FLASH
J 0
(-1100 3100);
DISPLAY 1.021277 (-1100 3100);
PAINT ORANGE (-1100 3100);
DISPLAY INVISIBLE (-1100 3100);
FORCEPROP 2 LAST CDS_LOCATION C2T2
J 0
(-1100 2900);
DISPLAY 0.617021 (-1100 2900);
PAINT AQUA (-1100 2900);
DISPLAY INVISIBLE (-1100 2900);
FORCEPROP 2 LAST CDS_SEC 1
J 0
(-1100 2950);
PAINT ORANGE (-1100 2950);
DISPLAY INVISIBLE (-1100 2950);
FORCEPROP 2 LAST SEC 1
J 0
(-1100 3000);
DISPLAY 0.680851 (-1100 3000);
PAINT MONO (-1100 3000);
DISPLAY INVISIBLE (-1100 3000);
FORCEPROP 2 LAST SEC_TYPE 0402V
J 0
(-1100 3000);
DISPLAY 1.021277 (-1100 3000);
PAINT ORANGE (-1100 3000);
DISPLAY INVISIBLE (-1100 3000);
FORCEPROP 1 LAST PATH I131
J 0
(-1100 2950);
DISPLAY 0.978723 (-1100 2950);
PAINT WHITE (-1100 2950);
DISPLAY INVISIBLE (-1100 2950);
FORCEPROP 0 LAST ROOM M_2
J 0
(-1100 3000);
DISPLAY 1.021277 (-1100 3000);
PAINT ORANGE (-1100 3000);
DISPLAY INVISIBLE (-1100 3000);
FORCEPROP 2 LAST CDS_LIB dev_discrete
J 0
(-1150 2800);
PAINT ORANGE (-1150 2800);
DISPLAY INVISIBLE (-1150 2800);
FORCEADD CAP_A..1
(-1400 2800);
FORCEPROP 1 LAST LOCATION C2T4
J 0
(-1350 2900);
DISPLAY 0.617021 (-1350 2900);
PAINT AQUA (-1350 2900);
FORCEPROP 1 LAST PART_NUMBER A36096-030
J 0
(-1350 2650);
DISPLAY 0.617021 (-1350 2650);
PAINT BLUE (-1350 2650);
FORCEPROP 1 LAST VALUE 0.1UF
J 0
(-1350 2850);
DISPLAY 0.617021 (-1350 2850);
PAINT SKYBLUE (-1350 2850);
FORCEPROP 1 LAST TOLERANCE 10%
J 0
(-1350 2750);
DISPLAY 0.617021 (-1350 2750);
PAINT SKYBLUE (-1350 2750);
FORCEPROP 1 LAST PACK_TYPE 0402V
J 0
(-1350 2600);
DISPLAY 0.617021 (-1350 2600);
PAINT SKYBLUE (-1350 2600);
FORCEPROP 1 LAST VOLTAGE 16V
J 0
(-1350 2800);
DISPLAY 0.617021 (-1350 2800);
PAINT SKYBLUE (-1350 2800);
FORCEPROP 1 LAST MATERIAL X7R
J 0
(-1350 2700);
DISPLAY 0.617021 (-1350 2700);
PAINT SKYBLUE (-1350 2700);
FORCEPROP 1 LASTPIN (-1400 2900) $PN 1
J 0
(-1390 2880);
DISPLAY 0.617021 (-1390 2880);
PAINT ORANGE (-1390 2880);
FORCEPROP 1 LASTPIN (-1400 2700) $PN 2
J 0
(-1390 2680);
DISPLAY 0.617021 (-1390 2680);
PAINT ORANGE (-1390 2680);
FORCEPROP 0 LAST BOM_COST SD_FLASH
J 0
(-1350 3100);
DISPLAY 1.021277 (-1350 3100);
PAINT ORANGE (-1350 3100);
DISPLAY INVISIBLE (-1350 3100);
FORCEPROP 2 LAST SEC_TYPE 0402V
J 0
(-1350 3000);
DISPLAY 1.021277 (-1350 3000);
PAINT ORANGE (-1350 3000);
DISPLAY INVISIBLE (-1350 3000);
FORCEPROP 2 LAST SEC 1
J 0
(-1350 3000);
DISPLAY 0.680851 (-1350 3000);
PAINT MONO (-1350 3000);
DISPLAY INVISIBLE (-1350 3000);
FORCEPROP 2 LAST CDS_SEC 1
J 0
(-1350 2950);
PAINT ORANGE (-1350 2950);
DISPLAY INVISIBLE (-1350 2950);
FORCEPROP 0 LAST ROOM M_2
J 0
(-1350 3000);
DISPLAY 1.021277 (-1350 3000);
PAINT ORANGE (-1350 3000);
DISPLAY INVISIBLE (-1350 3000);
FORCEPROP 1 LAST PATH I132
J 0
(-1350 2950);
DISPLAY 0.978723 (-1350 2950);
PAINT WHITE (-1350 2950);
DISPLAY INVISIBLE (-1350 2950);
FORCEPROP 2 LAST CDS_LOCATION C2T4
J 0
(-1350 2900);
DISPLAY 0.617021 (-1350 2900);
PAINT AQUA (-1350 2900);
DISPLAY INVISIBLE (-1350 2900);
FORCEPROP 2 LAST CDS_LIB dev_discrete
J 0
(-1400 2800);
PAINT ORANGE (-1400 2800);
DISPLAY INVISIBLE (-1400 2800);
FORCEADD P3V3..1
(-1650 3025);
FORCEPROP 3 LASTPIN (-1650 2975) SIG_NAME P3V3\g
J 0
(-1640 2985);
DISPLAY 0.659574 (-1640 2985);
PAINT MONO (-1640 2985);
DISPLAY INVISIBLE (-1640 2985);
FORCEPROP 1 LAST PATH I133
J 0
(-1605 3027);
DISPLAY 0.340426 (-1605 3027);
PAINT GREEN (-1605 3027);
DISPLAY INVISIBLE (-1605 3027);
FORCEPROP 1 LAST SIZE 1B
J 0
(-1605 3047);
DISPLAY 0.340426 (-1605 3047);
PAINT GREEN (-1605 3047);
DISPLAY INVISIBLE (-1605 3047);
FORCEPROP 1 LAST BODY_TYPE PLUMBING
J 0
(-1695 2982);
DISPLAY 0.340426 (-1695 2982);
PAINT GREEN (-1695 2982);
DISPLAY INVISIBLE (-1695 2982);
FORCEPROP 2 LAST CDS_LIB mstr_symbols
J 0
(-1650 3025);
PAINT MONO (-1650 3025);
DISPLAY INVISIBLE (-1650 3025);
FORCEPROP 1 LAST VOLTAGE 3.3V
J 0
(-1695 2982);
DISPLAY 0.340426 (-1695 2982);
PAINT SKYBLUE (-1695 2982);
DISPLAY INVISIBLE (-1695 2982);
FORCEPROP 1 LAST HDL_POWER P3V3
J 0
(-1975 2900);
DISPLAY 0.872340 (-1975 2900);
PAINT ORANGE (-1975 2900);
DISPLAY INVISIBLE (-1975 2900);
FORCEADD GND..1
(-1650 2575);
FORCEPROP 3 LASTPIN (-1650 2625) SIG_NAME GND\g
J 0
(-1640 2635);
DISPLAY 0.659574 (-1640 2635);
PAINT MONO (-1640 2635);
DISPLAY INVISIBLE (-1640 2635);
FORCEPROP 1 LAST PATH I134
J 0
(-1575 2575);
DISPLAY 0.872340 (-1575 2575);
PAINT AQUA (-1575 2575);
DISPLAY INVISIBLE (-1575 2575);
FORCEPROP 1 LAST HDL_POWER GND
J 0
(-1650 2725);
DISPLAY 0.872340 (-1650 2725);
PAINT GREEN (-1650 2725);
DISPLAY INVISIBLE (-1650 2725);
FORCEPROP 2 LAST CDS_LIB mstr_symbols
J 0
(-1650 2575);
PAINT MONO (-1650 2575);
DISPLAY INVISIBLE (-1650 2575);
FORCEPROP 1 LAST SIZE 1B
J 0
(-1575 2525);
DISPLAY 0.872340 (-1575 2525);
PAINT AQUA (-1575 2525);
DISPLAY INVISIBLE (-1575 2525);
FORCEPROP 1 LAST VOLTAGE 0.0V
J 0
(-1695 2532);
DISPLAY 0.340426 (-1695 2532);
PAINT SKYBLUE (-1695 2532);
DISPLAY INVISIBLE (-1695 2532);
FORCEPROP 1 LAST BODY_TYPE PLUMBING
J 0
(-1695 2532);
DISPLAY 0.340426 (-1695 2532);
PAINT GREEN (-1695 2532);
DISPLAY INVISIBLE (-1695 2532);
FORCEADD CAP_A..1
(-1650 2800);
FORCEPROP 1 LAST PART_NUMBER A36096-030
J 0
(-1600 2650);
DISPLAY 0.617021 (-1600 2650);
PAINT BLUE (-1600 2650);
FORCEPROP 1 LAST LOCATION C2T5
J 0
(-1600 2900);
DISPLAY 0.617021 (-1600 2900);
PAINT AQUA (-1600 2900);
FORCEPROP 1 LAST VALUE 0.1UF
J 0
(-1600 2850);
DISPLAY 0.617021 (-1600 2850);
PAINT SKYBLUE (-1600 2850);
FORCEPROP 1 LAST TOLERANCE 10%
J 0
(-1600 2750);
DISPLAY 0.617021 (-1600 2750);
PAINT SKYBLUE (-1600 2750);
FORCEPROP 1 LAST PACK_TYPE 0402V
J 0
(-1600 2600);
DISPLAY 0.617021 (-1600 2600);
PAINT SKYBLUE (-1600 2600);
FORCEPROP 1 LAST VOLTAGE 16V
J 0
(-1600 2800);
DISPLAY 0.617021 (-1600 2800);
PAINT SKYBLUE (-1600 2800);
FORCEPROP 1 LAST MATERIAL X7R
J 0
(-1600 2700);
DISPLAY 0.617021 (-1600 2700);
PAINT SKYBLUE (-1600 2700);
FORCEPROP 1 LASTPIN (-1650 2900) $PN 1
J 0
(-1640 2880);
DISPLAY 0.617021 (-1640 2880);
PAINT ORANGE (-1640 2880);
FORCEPROP 1 LASTPIN (-1650 2700) $PN 2
J 0
(-1640 2680);
DISPLAY 0.617021 (-1640 2680);
PAINT ORANGE (-1640 2680);
FORCEPROP 0 LAST BOM_COST SD_FLASH
J 0
(-1600 3100);
DISPLAY 1.021277 (-1600 3100);
PAINT ORANGE (-1600 3100);
DISPLAY INVISIBLE (-1600 3100);
FORCEPROP 2 LAST SEC_TYPE 0402V
J 0
(-1600 3000);
DISPLAY 1.021277 (-1600 3000);
PAINT ORANGE (-1600 3000);
DISPLAY INVISIBLE (-1600 3000);
FORCEPROP 2 LAST SEC 1
J 0
(-1600 3000);
DISPLAY 0.680851 (-1600 3000);
PAINT MONO (-1600 3000);
DISPLAY INVISIBLE (-1600 3000);
FORCEPROP 2 LAST CDS_SEC 1
J 0
(-1600 2950);
PAINT ORANGE (-1600 2950);
DISPLAY INVISIBLE (-1600 2950);
FORCEPROP 0 LAST ROOM M_2
J 0
(-1600 3000);
DISPLAY 1.021277 (-1600 3000);
PAINT ORANGE (-1600 3000);
DISPLAY INVISIBLE (-1600 3000);
FORCEPROP 1 LAST PATH I135
J 0
(-1600 2950);
DISPLAY 0.978723 (-1600 2950);
PAINT WHITE (-1600 2950);
DISPLAY INVISIBLE (-1600 2950);
FORCEPROP 2 LAST CDS_LOCATION C2T5
J 0
(-1600 2900);
DISPLAY 0.617021 (-1600 2900);
PAINT AQUA (-1600 2900);
DISPLAY INVISIBLE (-1600 2900);
FORCEPROP 2 LAST CDS_LIB dev_discrete
J 0
(-1650 2800);
PAINT ORANGE (-1650 2800);
DISPLAY INVISIBLE (-1650 2800);
FORCEADD RES..2
(-3300 3300);
FORCEPROP 1 LASTPIN (-3300 3200) $PN 2
J 0
(-3295 3210);
DISPLAY 0.617021 (-3295 3210);
PAINT ORANGE (-3295 3210);
FORCEPROP 1 LAST PACK_TYPE 0402
J 0
(-3260 3125);
DISPLAY 0.617021 (-3260 3125);
PAINT SKYBLUE (-3260 3125);
FORCEPROP 1 LAST MATERIAL CHIP
J 0
(-3260 3225);
DISPLAY 0.617021 (-3260 3225);
PAINT SKYBLUE (-3260 3225);
FORCEPROP 1 LAST WATTAGE 1/16W
J 0
(-3260 3275);
DISPLAY 0.617021 (-3260 3275);
PAINT SKYBLUE (-3260 3275);
FORCEPROP 1 LAST TOLERANCE 1%
J 0
(-3255 3325);
DISPLAY 0.617021 (-3255 3325);
PAINT SKYBLUE (-3255 3325);
FORCEPROP 1 LASTPIN (-3300 3400) $PN 1
J 0
(-3295 3362);
DISPLAY 0.617021 (-3295 3362);
PAINT ORANGE (-3295 3362);
FORCEPROP 1 LAST LOCATION R8F36
J 0
(-3255 3425);
DISPLAY 0.617021 (-3255 3425);
PAINT AQUA (-3255 3425);
FORCEPROP 1 LAST VALUE 10.0K
J 0
(-3255 3375);
DISPLAY 0.617021 (-3255 3375);
PAINT SKYBLUE (-3255 3375);
FORCEPROP 1 LAST PART_NUMBER G21796-016
J 0
(-3260 3175);
DISPLAY 0.617021 (-3260 3175);
PAINT BLUE (-3260 3175);
FORCEPROP 2 LAST CDS_LIB mstr_discrete
J 0
(-3300 3300);
PAINT ORANGE (-3300 3300);
DISPLAY INVISIBLE (-3300 3300);
FORCEPROP 0 LAST ROOM M_2
J 0
(-3250 3525);
DISPLAY 1.021277 (-3250 3525);
PAINT ORANGE (-3250 3525);
DISPLAY INVISIBLE (-3250 3525);
FORCEPROP 1 LAST PATH I136
J 0
(-3250 3475);
DISPLAY 0.978723 (-3250 3475);
PAINT WHITE (-3250 3475);
DISPLAY INVISIBLE (-3250 3475);
FORCEPROP 2 LAST SEC_TYPE 0402
J 0
(-3250 3525);
DISPLAY 1.021277 (-3250 3525);
PAINT ORANGE (-3250 3525);
DISPLAY INVISIBLE (-3250 3525);
FORCEPROP 2 LAST SEC 1
J 0
(-3250 3525);
DISPLAY 0.680851 (-3250 3525);
PAINT MONO (-3250 3525);
DISPLAY INVISIBLE (-3250 3525);
FORCEPROP 0 LAST BOM_COST ST_FLASH
J 0
(-3250 3625);
DISPLAY 1.021277 (-3250 3625);
PAINT ORANGE (-3250 3625);
DISPLAY INVISIBLE (-3250 3625);
FORCEADD P3V3..1
(-3300 3500);
FORCEPROP 3 LASTPIN (-3300 3450) SIG_NAME P3V3\g
J 0
(-3290 3460);
DISPLAY 0.659574 (-3290 3460);
PAINT MONO (-3290 3460);
DISPLAY INVISIBLE (-3290 3460);
FORCEPROP 1 LAST HDL_POWER P3V3
J 0
(-3625 3375);
DISPLAY 0.872340 (-3625 3375);
PAINT ORANGE (-3625 3375);
DISPLAY INVISIBLE (-3625 3375);
FORCEPROP 1 LAST BODY_TYPE PLUMBING
J 0
(-3345 3457);
DISPLAY 0.340426 (-3345 3457);
PAINT GREEN (-3345 3457);
DISPLAY INVISIBLE (-3345 3457);
FORCEPROP 1 LAST VOLTAGE 3.3V
J 0
(-3345 3457);
DISPLAY 0.340426 (-3345 3457);
PAINT SKYBLUE (-3345 3457);
DISPLAY INVISIBLE (-3345 3457);
FORCEPROP 1 LAST PATH I137
J 0
(-3255 3502);
DISPLAY 0.340426 (-3255 3502);
PAINT GREEN (-3255 3502);
DISPLAY INVISIBLE (-3255 3502);
FORCEPROP 2 LAST CDS_LIB mstr_symbols
J 0
(-3300 3500);
PAINT ORANGE (-3300 3500);
DISPLAY INVISIBLE (-3300 3500);
FORCEPROP 1 LAST SIZE 1B
J 0
(-3255 3522);
DISPLAY 0.340426 (-3255 3522);
PAINT GREEN (-3255 3522);
DISPLAY INVISIBLE (-3255 3522);
FORCEADD SCONN75K_H17033002..2
(-5850 3275);
FORCEPROP 1 LAST PART_NUMBER H17033-002
J 0
(-6550 1975);
DISPLAY 0.617021 (-6550 1975);
PAINT BLUE (-6550 1975);
FORCEPROP 2 LASTPIN (-6600 2975) $PN 67
J 2
(-6610 2985);
DISPLAY 0.617021 (-6610 2985);
PAINT ORANGE (-6610 2985);
FORCEPROP 2 LASTPIN (-6600 2925) $PN 58
J 2
(-6610 2935);
DISPLAY 0.617021 (-6610 2935);
PAINT ORANGE (-6610 2935);
FORCEPROP 2 LASTPIN (-6600 2875) $PN 56
J 2
(-6610 2885);
DISPLAY 0.617021 (-6610 2885);
PAINT ORANGE (-6610 2885);
FORCEPROP 2 LASTPIN (-6600 2825) $PN 48
J 2
(-6610 2835);
DISPLAY 0.617021 (-6610 2835);
PAINT ORANGE (-6610 2835);
FORCEPROP 2 LASTPIN (-6600 2775) $PN 46
J 2
(-6610 2785);
DISPLAY 0.617021 (-6610 2785);
PAINT ORANGE (-6610 2785);
FORCEPROP 2 LASTPIN (-6600 2725) $PN 44
J 2
(-6610 2735);
DISPLAY 0.617021 (-6610 2735);
PAINT ORANGE (-6610 2735);
FORCEPROP 2 LASTPIN (-6600 2675) $PN 42
J 2
(-6610 2685);
DISPLAY 0.617021 (-6610 2685);
PAINT ORANGE (-6610 2685);
FORCEPROP 2 LASTPIN (-6600 2625) $PN 40
J 2
(-6610 2635);
DISPLAY 0.617021 (-6610 2635);
PAINT ORANGE (-6610 2635);
FORCEPROP 2 LASTPIN (-6600 2575) $PN 36
J 2
(-6610 2585);
DISPLAY 0.617021 (-6610 2585);
PAINT ORANGE (-6610 2585);
FORCEPROP 2 LASTPIN (-6600 2525) $PN 34
J 2
(-6610 2535);
DISPLAY 0.617021 (-6610 2535);
PAINT ORANGE (-6610 2535);
FORCEPROP 2 LASTPIN (-6600 2475) $PN 32
J 2
(-6610 2485);
DISPLAY 0.617021 (-6610 2485);
PAINT ORANGE (-6610 2485);
FORCEPROP 2 LASTPIN (-6600 2425) $PN 30
J 2
(-6610 2435);
DISPLAY 0.617021 (-6610 2435);
PAINT ORANGE (-6610 2435);
FORCEPROP 2 LASTPIN (-6600 2375) $PN 28
J 2
(-6610 2385);
DISPLAY 0.617021 (-6610 2385);
PAINT ORANGE (-6610 2385);
FORCEPROP 2 LASTPIN (-6600 2325) $PN 26
J 2
(-6610 2335);
DISPLAY 0.617021 (-6610 2335);
PAINT ORANGE (-6610 2335);
FORCEPROP 2 LASTPIN (-6600 2275) $PN 24
J 2
(-6610 2285);
DISPLAY 0.617021 (-6610 2285);
PAINT ORANGE (-6610 2285);
FORCEPROP 2 LASTPIN (-6600 2225) $PN 22
J 2
(-6610 2235);
DISPLAY 0.617021 (-6610 2235);
PAINT ORANGE (-6610 2235);
FORCEPROP 2 LASTPIN (-6600 2175) $PN 20
J 2
(-6610 2185);
DISPLAY 0.617021 (-6610 2185);
PAINT ORANGE (-6610 2185);
FORCEPROP 2 LASTPIN (-6600 2125) $PN 8
J 2
(-6610 2135);
DISPLAY 0.617021 (-6610 2135);
PAINT ORANGE (-6610 2135);
FORCEPROP 2 LASTPIN (-6600 2075) $PN 6
J 2
(-6610 2085);
DISPLAY 0.617021 (-6610 2085);
PAINT ORANGE (-6610 2085);
FORCEPROP 2 LASTPIN (-6600 3525) $PN 49
J 2
(-6610 3535);
DISPLAY 0.617021 (-6610 3535);
PAINT ORANGE (-6610 3535);
FORCEPROP 2 LASTPIN (-6600 3475) $PN 47
J 2
(-6610 3485);
DISPLAY 0.617021 (-6610 3485);
PAINT ORANGE (-6610 3485);
FORCEPROP 2 LASTPIN (-6600 3725) $PN 43
J 2
(-6610 3735);
DISPLAY 0.617021 (-6610 3735);
PAINT ORANGE (-6610 3735);
FORCEPROP 2 LASTPIN (-6600 3675) $PN 41
J 2
(-6610 3685);
DISPLAY 0.617021 (-6610 3685);
PAINT ORANGE (-6610 3685);
FORCEPROP 2 LASTPIN (-6600 3175) $PN 69
J 2
(-6610 3185);
DISPLAY 0.617021 (-6610 3185);
PAINT ORANGE (-6610 3185);
FORCEPROP 2 LASTPIN (-6600 3325) $PN 10
J 2
(-6610 3335);
DISPLAY 0.617021 (-6610 3335);
PAINT ORANGE (-6610 3335);
FORCEPROP 2 LASTPIN (-6600 4025) $PN 14
J 2
(-6610 4035);
DISPLAY 0.617021 (-6610 4035);
PAINT ORANGE (-6610 4035);
FORCEPROP 2 LASTPIN (-6600 3975) $PN 12
J 2
(-6610 3985);
DISPLAY 0.617021 (-6610 3985);
PAINT ORANGE (-6610 3985);
FORCEPROP 2 LASTPIN (-6600 3925) $PN 4
J 2
(-6610 3935);
DISPLAY 0.617021 (-6610 3935);
PAINT ORANGE (-6610 3935);
FORCEPROP 2 LASTPIN (-6600 3875) $PN 2
J 2
(-6610 3885);
DISPLAY 0.617021 (-6610 3885);
PAINT ORANGE (-6610 3885);
FORCEPROP 2 LASTPIN (-5100 2125) $PN 1
J 0
(-5090 2135);
DISPLAY 0.617021 (-5090 2135);
PAINT ORANGE (-5090 2135);
FORCEPROP 2 LASTPIN (-5100 2175) $PN 3
J 0
(-5090 2185);
DISPLAY 0.617021 (-5090 2185);
PAINT ORANGE (-5090 2185);
FORCEPROP 2 LASTPIN (-5100 2225) $PN 9
J 0
(-5090 2235);
DISPLAY 0.617021 (-5090 2235);
PAINT ORANGE (-5090 2235);
FORCEPROP 2 LASTPIN (-5100 2275) $PN 15
J 0
(-5090 2285);
DISPLAY 0.617021 (-5090 2285);
PAINT ORANGE (-5090 2285);
FORCEPROP 2 LASTPIN (-5100 2325) $PN 21
J 0
(-5090 2335);
DISPLAY 0.617021 (-5090 2335);
PAINT ORANGE (-5090 2335);
FORCEPROP 2 LASTPIN (-5100 2375) $PN 27
J 0
(-5090 2385);
DISPLAY 0.617021 (-5090 2385);
PAINT ORANGE (-5090 2385);
FORCEPROP 2 LASTPIN (-5100 2425) $PN 33
J 0
(-5090 2435);
DISPLAY 0.617021 (-5090 2435);
PAINT ORANGE (-5090 2435);
FORCEPROP 2 LASTPIN (-5100 2475) $PN 39
J 0
(-5090 2485);
DISPLAY 0.617021 (-5090 2485);
PAINT ORANGE (-5090 2485);
FORCEPROP 2 LASTPIN (-5100 2525) $PN 45
J 0
(-5090 2535);
DISPLAY 0.617021 (-5090 2535);
PAINT ORANGE (-5090 2535);
FORCEPROP 2 LASTPIN (-5100 2575) $PN 51
J 0
(-5090 2585);
DISPLAY 0.617021 (-5090 2585);
PAINT ORANGE (-5090 2585);
FORCEPROP 2 LASTPIN (-5100 2625) $PN 57
J 0
(-5090 2635);
DISPLAY 0.617021 (-5090 2635);
PAINT ORANGE (-5090 2635);
FORCEPROP 2 LASTPIN (-5100 2675) $PN 71
J 0
(-5090 2685);
DISPLAY 0.617021 (-5090 2685);
PAINT ORANGE (-5090 2685);
FORCEPROP 2 LASTPIN (-5100 2725) $PN 73
J 0
(-5090 2735);
DISPLAY 0.617021 (-5090 2735);
PAINT ORANGE (-5090 2735);
FORCEPROP 2 LASTPIN (-5100 2775) $PN 75
J 0
(-5090 2785);
DISPLAY 0.617021 (-5090 2785);
PAINT ORANGE (-5090 2785);
FORCEPROP 2 LASTPIN (-5100 2875) $PN MP2
J 0
(-5090 2885);
DISPLAY 0.617021 (-5090 2885);
PAINT ORANGE (-5090 2885);
FORCEPROP 2 LASTPIN (-5100 2925) $PN MP1
J 0
(-5090 2935);
DISPLAY 0.617021 (-5090 2935);
PAINT ORANGE (-5090 2935);
FORCEPROP 2 LASTPIN (-5100 3025) $PN 53
J 0
(-5090 3035);
DISPLAY 0.617021 (-5090 3035);
PAINT ORANGE (-5090 3035);
FORCEPROP 2 LASTPIN (-5100 3225) $PN 52
J 0
(-5090 3235);
DISPLAY 0.617021 (-5090 3235);
PAINT ORANGE (-5090 3235);
FORCEPROP 2 LASTPIN (-5100 3175) $PN 54
J 0
(-5090 3185);
DISPLAY 0.617021 (-5090 3185);
PAINT ORANGE (-5090 3185);
FORCEPROP 2 LASTPIN (-5100 3075) $PN 55
J 0
(-5090 3085);
DISPLAY 0.617021 (-5090 3085);
PAINT ORANGE (-5090 3085);
FORCEPROP 2 LASTPIN (-5100 3525) $PN 68
J 0
(-5090 3535);
DISPLAY 0.617021 (-5090 3535);
PAINT ORANGE (-5090 3535);
FORCEPROP 2 LASTPIN (-5100 3325) $PN 50
J 0
(-5090 3335);
DISPLAY 0.617021 (-5090 3335);
PAINT ORANGE (-5090 3335);
FORCEPROP 2 LASTPIN (-5100 3425) $PN 38
J 0
(-5090 3435);
DISPLAY 0.617021 (-5090 3435);
PAINT ORANGE (-5090 3435);
FORCEPROP 2 LASTPIN (-5100 3675) $PN 37
J 0
(-5090 3685);
DISPLAY 0.617021 (-5090 3685);
PAINT ORANGE (-5090 3685);
FORCEPROP 2 LASTPIN (-5100 3625) $PN 35
J 0
(-5090 3635);
DISPLAY 0.617021 (-5090 3635);
PAINT ORANGE (-5090 3635);
FORCEPROP 2 LASTPIN (-5100 3775) $PN 31
J 0
(-5090 3785);
DISPLAY 0.617021 (-5090 3785);
PAINT ORANGE (-5090 3785);
FORCEPROP 2 LASTPIN (-5100 3725) $PN 29
J 0
(-5090 3735);
DISPLAY 0.617021 (-5090 3735);
PAINT ORANGE (-5090 3735);
FORCEPROP 2 LASTPIN (-5100 3925) $PN 25
J 0
(-5090 3935);
DISPLAY 0.617021 (-5090 3935);
PAINT ORANGE (-5090 3935);
FORCEPROP 2 LASTPIN (-5100 3875) $PN 23
J 0
(-5090 3885);
DISPLAY 0.617021 (-5090 3885);
PAINT ORANGE (-5090 3885);
FORCEPROP 2 LASTPIN (-5100 3975) $PN 17
J 0
(-5090 3985);
DISPLAY 0.617021 (-5090 3985);
PAINT ORANGE (-5090 3985);
FORCEPROP 2 LASTPIN (-5100 4025) $PN 19
J 0
(-5090 4035);
DISPLAY 0.617021 (-5090 4035);
PAINT ORANGE (-5090 4035);
FORCEPROP 2 LASTPIN (-6600 4075) $PN 16
J 2
(-6610 4085);
DISPLAY 0.617021 (-6610 4085);
PAINT ORANGE (-6610 4085);
FORCEPROP 2 LASTPIN (-6600 4225) $PN 72
J 2
(-6610 4235);
DISPLAY 0.617021 (-6610 4235);
PAINT ORANGE (-6610 4235);
FORCEPROP 2 LASTPIN (-6600 4175) $PN 70
J 2
(-6610 4185);
DISPLAY 0.617021 (-6610 4185);
PAINT ORANGE (-6610 4185);
FORCEPROP 2 LASTPIN (-6600 4125) $PN 18
J 2
(-6610 4135);
DISPLAY 0.617021 (-6610 4135);
PAINT ORANGE (-6610 4135);
FORCEPROP 2 LASTPIN (-5100 4175) $PN 13
J 0
(-5090 4185);
DISPLAY 0.617021 (-5090 4185);
PAINT ORANGE (-5090 4185);
FORCEPROP 2 LASTPIN (-5100 4125) $PN 11
J 0
(-5090 4135);
DISPLAY 0.617021 (-5090 4135);
PAINT ORANGE (-5090 4135);
FORCEPROP 2 LASTPIN (-5100 4275) $PN 7
J 0
(-5090 4285);
DISPLAY 0.617021 (-5090 4285);
PAINT ORANGE (-5090 4285);
FORCEPROP 2 LASTPIN (-5100 4225) $PN 5
J 0
(-5090 4235);
DISPLAY 0.617021 (-5090 4235);
PAINT ORANGE (-5090 4235);
FORCEPROP 1 LAST LOCATION J8F1
J 0
(-6550 4625);
DISPLAY 0.617021 (-6550 4625);
PAINT AQUA (-6550 4625);
FORCEPROP 1 LAST MATERIAL SCONN
J 0
(-6550 4575);
DISPLAY 0.617021 (-6550 4575);
PAINT SKYBLUE (-6550 4575);
FORCEPROP 2 LASTPIN (-6600 4275) $PN 74
J 2
(-6610 4285);
DISPLAY 0.617021 (-6610 4285);
PAINT ORANGE (-6610 4285);
FORCEPROP 1 LAST CDS_LMAN_SYM_OUTLINE -700,1250,700,-1250
J 0
(-5850 3275);
DISPLAY 0.468085 (-5850 3275);
PAINT GREEN (-5850 3275);
DISPLAY INVISIBLE (-5850 3275);
FORCEPROP 2 LAST CDS_LIB mstr_sconn
J 0
(-5850 3275);
PAINT ORANGE (-5850 3275);
DISPLAY INVISIBLE (-5850 3275);
FORCEPROP 1 LAST PACK_TYPE SMT1
J 0
(-6550 4675);
PAINT SKYBLUE (-6550 4675);
DISPLAY INVISIBLE (-6550 4675);
FORCEPROP 2 LAST CDS_LOCATION J8F1
J 0
(-6550 4625);
DISPLAY 0.617021 (-6550 4625);
PAINT AQUA (-6550 4625);
DISPLAY INVISIBLE (-6550 4625);
FORCEPROP 2 LAST SEC 1
J 0
(-6550 4675);
DISPLAY 0.680851 (-6550 4675);
PAINT MONO (-6550 4675);
DISPLAY INVISIBLE (-6550 4675);
FORCEPROP 0 LAST BOM_COST ST_FLASH
J 0
(-6550 4725);
DISPLAY 1.021277 (-6550 4725);
PAINT ORANGE (-6550 4725);
DISPLAY INVISIBLE (-6550 4725);
FORCEPROP 2 LAST SEC_TYPE SMT1
J 0
(-6550 4675);
DISPLAY 1.021277 (-6550 4675);
PAINT ORANGE (-6550 4675);
DISPLAY INVISIBLE (-6550 4675);
FORCEPROP 0 LAST ROOM M_2
J 0
(-6550 4675);
DISPLAY 1.021277 (-6550 4675);
PAINT ORANGE (-6550 4675);
DISPLAY INVISIBLE (-6550 4675);
FORCEPROP 1 LAST PATH I53
J 0
(-5850 4575);
PAINT GREEN (-5850 4575);
DISPLAY INVISIBLE (-5850 4575);
FORCEADD GND..1
(-5000 1875);
FORCEPROP 3 LASTPIN (-5000 1925) SIG_NAME GND\g
J 0
(-4990 1935);
DISPLAY 0.659574 (-4990 1935);
PAINT MONO (-4990 1935);
DISPLAY INVISIBLE (-4990 1935);
FORCEPROP 1 LAST PATH I54
J 0
(-4925 1875);
DISPLAY 0.872340 (-4925 1875);
PAINT AQUA (-4925 1875);
DISPLAY INVISIBLE (-4925 1875);
FORCEPROP 1 LAST BODY_TYPE PLUMBING
J 0
(-5045 1832);
DISPLAY 0.340426 (-5045 1832);
PAINT GREEN (-5045 1832);
DISPLAY INVISIBLE (-5045 1832);
FORCEPROP 1 LAST SIZE 1B
J 0
(-4925 1825);
DISPLAY 0.872340 (-4925 1825);
PAINT AQUA (-4925 1825);
DISPLAY INVISIBLE (-4925 1825);
FORCEPROP 2 LAST CDS_LIB mstr_symbols
J 0
(-5000 1875);
PAINT ORANGE (-5000 1875);
DISPLAY INVISIBLE (-5000 1875);
FORCEPROP 1 LAST VOLTAGE 0.0V
J 0
(-5045 1832);
DISPLAY 0.340426 (-5045 1832);
PAINT SKYBLUE (-5045 1832);
DISPLAY INVISIBLE (-5045 1832);
FORCEPROP 1 LAST HDL_POWER GND
J 0
(-5000 2025);
DISPLAY 0.872340 (-5000 2025);
PAINT GREEN (-5000 2025);
DISPLAY INVISIBLE (-5000 2025);
FORCEADD P3V3..1
(-6725 4775);
FORCEPROP 3 LASTPIN (-6725 4725) SIG_NAME P3V3\g
J 0
(-6715 4735);
DISPLAY 0.659574 (-6715 4735);
PAINT MONO (-6715 4735);
DISPLAY INVISIBLE (-6715 4735);
FORCEPROP 1 LAST VOLTAGE 3.3V
J 0
(-6770 4732);
DISPLAY 0.340426 (-6770 4732);
PAINT SKYBLUE (-6770 4732);
DISPLAY INVISIBLE (-6770 4732);
FORCEPROP 1 LAST SIZE 1B
J 0
(-6680 4797);
DISPLAY 0.340426 (-6680 4797);
PAINT GREEN (-6680 4797);
DISPLAY INVISIBLE (-6680 4797);
FORCEPROP 2 LAST CDS_LIB mstr_symbols
J 0
(-6725 4775);
PAINT ORANGE (-6725 4775);
DISPLAY INVISIBLE (-6725 4775);
FORCEPROP 1 LAST BODY_TYPE PLUMBING
J 0
(-6770 4732);
DISPLAY 0.340426 (-6770 4732);
PAINT GREEN (-6770 4732);
DISPLAY INVISIBLE (-6770 4732);
FORCEPROP 1 LAST PATH I55
J 0
(-6680 4777);
DISPLAY 0.340426 (-6680 4777);
PAINT GREEN (-6680 4777);
DISPLAY INVISIBLE (-6680 4777);
FORCEPROP 1 LAST HDL_POWER P3V3
J 0
(-7050 4650);
DISPLAY 0.872340 (-7050 4650);
PAINT ORANGE (-7050 4650);
DISPLAY INVISIBLE (-7050 4650);
FORCEADD CAP..2
(-3950 3625);
FORCEPROP 1 LAST VALUE 0.22UF
J 2
(-4175 3625);
DISPLAY 0.617021 (-4175 3625);
PAINT SKYBLUE (-4175 3625);
FORCEPROP 1 LAST LOCATION C2T11
J 1
(-4425 3625);
DISPLAY 0.617021 (-4425 3625);
PAINT AQUA (-4425 3625);
FORCEPROP 1 LAST TOLERANCE 10%
J 2
(-4075 3625);
DISPLAY 0.617021 (-4075 3625);
PAINT SKYBLUE (-4075 3625);
FORCEPROP 1 LASTPIN (-4050 3625) $PN 1
J 0
(-4060 3640);
DISPLAY 0.617021 (-4060 3640);
PAINT ORANGE (-4060 3640);
FORCEPROP 1 LASTPIN (-3850 3625) $PN 2
J 0
(-3865 3640);
DISPLAY 0.617021 (-3865 3640);
PAINT ORANGE (-3865 3640);
FORCEPROP 1 LAST MATERIAL X7R
J 0
(-3800 3625);
DISPLAY 0.617021 (-3800 3625);
PAINT SKYBLUE (-3800 3625);
FORCEPROP 1 LAST VOLTAGE 16V
J 0
(-3675 3625);
DISPLAY 0.617021 (-3675 3625);
PAINT SKYBLUE (-3675 3625);
FORCEPROP 1 LAST PACK_TYPE 0402
J 1
(-3525 3625);
DISPLAY 0.617021 (-3525 3625);
PAINT SKYBLUE (-3525 3625);
FORCEPROP 1 LAST PART_NUMBER A36096-155
J 2
(-3225 3625);
DISPLAY 0.617021 (-3225 3625);
PAINT BLUE (-3225 3625);
FORCEPROP 2 LAST CDS_LOCATION C2T11
J 1
(-4425 3625);
DISPLAY 0.617021 (-4425 3625);
PAINT AQUA (-4425 3625);
DISPLAY INVISIBLE (-4425 3625);
FORCEPROP 2 LAST CDS_LIB mstr_discrete
J 0
(-3950 3625);
PAINT ORANGE (-3950 3625);
DISPLAY INVISIBLE (-3950 3625);
FORCEPROP 1 LAST PATH I62
J 0
(-3950 3825);
DISPLAY 0.978723 (-3950 3825);
PAINT WHITE (-3950 3825);
DISPLAY INVISIBLE (-3950 3825);
FORCEPROP 2 LAST SEC_TYPE 0402
J 0
(-3950 3875);
DISPLAY 1.021277 (-3950 3875);
PAINT ORANGE (-3950 3875);
DISPLAY INVISIBLE (-3950 3875);
FORCEPROP 2 LAST SEC 1
J 0
(-3950 3875);
DISPLAY 0.680851 (-3950 3875);
PAINT MONO (-3950 3875);
DISPLAY INVISIBLE (-3950 3875);
FORCEPROP 0 LAST BOM_COST ST_FLASH
J 0
(-3225 3825);
DISPLAY 1.021277 (-3225 3825);
PAINT ORANGE (-3225 3825);
DISPLAY INVISIBLE (-3225 3825);
FORCEPROP 0 LAST ROOM M_2
J 0
(-3225 3725);
DISPLAY 1.021277 (-3225 3725);
PAINT ORANGE (-3225 3725);
DISPLAY INVISIBLE (-3225 3725);
FORCEADD CAP..2
(-3950 3675);
FORCEPROP 1 LAST VALUE 0.22UF
J 2
(-4175 3675);
DISPLAY 0.617021 (-4175 3675);
PAINT SKYBLUE (-4175 3675);
FORCEPROP 1 LAST LOCATION C2T10
J 1
(-4425 3675);
DISPLAY 0.617021 (-4425 3675);
PAINT AQUA (-4425 3675);
FORCEPROP 1 LAST TOLERANCE 10%
J 2
(-4075 3675);
DISPLAY 0.617021 (-4075 3675);
PAINT SKYBLUE (-4075 3675);
FORCEPROP 1 LASTPIN (-4050 3675) $PN 1
J 0
(-4060 3690);
DISPLAY 0.617021 (-4060 3690);
PAINT ORANGE (-4060 3690);
FORCEPROP 1 LASTPIN (-3850 3675) $PN 2
J 0
(-3865 3690);
DISPLAY 0.617021 (-3865 3690);
PAINT ORANGE (-3865 3690);
FORCEPROP 1 LAST MATERIAL X7R
J 0
(-3800 3675);
DISPLAY 0.617021 (-3800 3675);
PAINT SKYBLUE (-3800 3675);
FORCEPROP 1 LAST VOLTAGE 16V
J 0
(-3675 3675);
DISPLAY 0.617021 (-3675 3675);
PAINT SKYBLUE (-3675 3675);
FORCEPROP 1 LAST PACK_TYPE 0402
J 1
(-3525 3675);
DISPLAY 0.617021 (-3525 3675);
PAINT SKYBLUE (-3525 3675);
FORCEPROP 1 LAST PART_NUMBER A36096-155
J 2
(-3225 3675);
DISPLAY 0.617021 (-3225 3675);
PAINT BLUE (-3225 3675);
FORCEPROP 2 LAST CDS_LOCATION C2T10
J 1
(-4425 3675);
DISPLAY 0.617021 (-4425 3675);
PAINT AQUA (-4425 3675);
DISPLAY INVISIBLE (-4425 3675);
FORCEPROP 2 LAST CDS_LIB mstr_discrete
J 0
(-3950 3675);
PAINT ORANGE (-3950 3675);
DISPLAY INVISIBLE (-3950 3675);
FORCEPROP 1 LAST PATH I63
J 0
(-3950 3875);
DISPLAY 0.978723 (-3950 3875);
PAINT WHITE (-3950 3875);
DISPLAY INVISIBLE (-3950 3875);
FORCEPROP 2 LAST SEC_TYPE 0402
J 0
(-3950 3925);
DISPLAY 1.021277 (-3950 3925);
PAINT ORANGE (-3950 3925);
DISPLAY INVISIBLE (-3950 3925);
FORCEPROP 2 LAST SEC 1
J 0
(-3950 3925);
DISPLAY 0.680851 (-3950 3925);
PAINT MONO (-3950 3925);
DISPLAY INVISIBLE (-3950 3925);
FORCEPROP 0 LAST BOM_COST ST_FLASH
J 0
(-3225 3775);
DISPLAY 1.021277 (-3225 3775);
PAINT ORANGE (-3225 3775);
DISPLAY INVISIBLE (-3225 3775);
FORCEPROP 0 LAST ROOM M_2
J 0
(-3225 3775);
DISPLAY 1.021277 (-3225 3775);
PAINT ORANGE (-3225 3775);
DISPLAY INVISIBLE (-3225 3775);
FORCEADD CAP..2
(-3950 3925);
FORCEPROP 1 LAST VALUE 0.22UF
J 2
(-4175 3925);
DISPLAY 0.617021 (-4175 3925);
PAINT SKYBLUE (-4175 3925);
FORCEPROP 1 LAST LOCATION C2T13
J 1
(-4425 3925);
DISPLAY 0.617021 (-4425 3925);
PAINT AQUA (-4425 3925);
FORCEPROP 1 LAST TOLERANCE 10%
J 2
(-4075 3925);
DISPLAY 0.617021 (-4075 3925);
PAINT SKYBLUE (-4075 3925);
FORCEPROP 1 LASTPIN (-4050 3925) $PN 1
J 0
(-4060 3940);
DISPLAY 0.617021 (-4060 3940);
PAINT ORANGE (-4060 3940);
FORCEPROP 1 LASTPIN (-3850 3925) $PN 2
J 0
(-3865 3940);
DISPLAY 0.617021 (-3865 3940);
PAINT ORANGE (-3865 3940);
FORCEPROP 1 LAST MATERIAL X7R
J 0
(-3800 3925);
DISPLAY 0.617021 (-3800 3925);
PAINT SKYBLUE (-3800 3925);
FORCEPROP 1 LAST VOLTAGE 16V
J 0
(-3675 3925);
DISPLAY 0.617021 (-3675 3925);
PAINT SKYBLUE (-3675 3925);
FORCEPROP 1 LAST PACK_TYPE 0402
J 1
(-3525 3925);
DISPLAY 0.617021 (-3525 3925);
PAINT SKYBLUE (-3525 3925);
FORCEPROP 1 LAST PART_NUMBER A36096-155
J 2
(-3225 3925);
DISPLAY 0.617021 (-3225 3925);
PAINT BLUE (-3225 3925);
FORCEPROP 2 LAST CDS_LOCATION C2T13
J 1
(-4425 3925);
DISPLAY 0.617021 (-4425 3925);
PAINT AQUA (-4425 3925);
DISPLAY INVISIBLE (-4425 3925);
FORCEPROP 2 LAST CDS_LIB mstr_discrete
J 0
(-3950 3925);
PAINT ORANGE (-3950 3925);
DISPLAY INVISIBLE (-3950 3925);
FORCEPROP 0 LAST BOM_COST ST_FLASH
J 0
(-3225 4025);
DISPLAY 1.021277 (-3225 4025);
PAINT ORANGE (-3225 4025);
DISPLAY INVISIBLE (-3225 4025);
FORCEPROP 0 LAST ROOM M_2
J 0
(-3225 3975);
DISPLAY 1.021277 (-3225 3975);
PAINT ORANGE (-3225 3975);
DISPLAY INVISIBLE (-3225 3975);
FORCEPROP 1 LAST PATH I64
J 0
(-3950 4125);
DISPLAY 0.978723 (-3950 4125);
PAINT WHITE (-3950 4125);
DISPLAY INVISIBLE (-3950 4125);
FORCEPROP 2 LAST SEC_TYPE 0402
J 0
(-3950 4175);
DISPLAY 1.021277 (-3950 4175);
PAINT ORANGE (-3950 4175);
DISPLAY INVISIBLE (-3950 4175);
FORCEPROP 2 LAST SEC 1
J 0
(-3950 4175);
DISPLAY 0.680851 (-3950 4175);
PAINT MONO (-3950 4175);
DISPLAY INVISIBLE (-3950 4175);
FORCEADD CAP..2
(-3950 3875);
FORCEPROP 1 LAST TOLERANCE 10%
J 2
(-4075 3875);
DISPLAY 0.617021 (-4075 3875);
PAINT SKYBLUE (-4075 3875);
FORCEPROP 1 LASTPIN (-4050 3875) $PN 1
J 0
(-4060 3890);
DISPLAY 0.617021 (-4060 3890);
PAINT ORANGE (-4060 3890);
FORCEPROP 1 LASTPIN (-3850 3875) $PN 2
J 0
(-3865 3890);
DISPLAY 0.617021 (-3865 3890);
PAINT ORANGE (-3865 3890);
FORCEPROP 1 LAST MATERIAL X7R
J 0
(-3800 3875);
DISPLAY 0.617021 (-3800 3875);
PAINT SKYBLUE (-3800 3875);
FORCEPROP 1 LAST VOLTAGE 16V
J 0
(-3675 3875);
DISPLAY 0.617021 (-3675 3875);
PAINT SKYBLUE (-3675 3875);
FORCEPROP 1 LAST PACK_TYPE 0402
J 1
(-3525 3875);
DISPLAY 0.617021 (-3525 3875);
PAINT SKYBLUE (-3525 3875);
FORCEPROP 1 LAST PART_NUMBER A36096-155
J 2
(-3225 3875);
DISPLAY 0.617021 (-3225 3875);
PAINT BLUE (-3225 3875);
FORCEPROP 1 LAST LOCATION C2T14
J 1
(-4425 3875);
DISPLAY 0.617021 (-4425 3875);
PAINT AQUA (-4425 3875);
FORCEPROP 1 LAST VALUE 0.22UF
J 2
(-4175 3875);
DISPLAY 0.617021 (-4175 3875);
PAINT SKYBLUE (-4175 3875);
FORCEPROP 2 LAST CDS_LOCATION C2T14
J 1
(-4425 3875);
DISPLAY 0.617021 (-4425 3875);
PAINT AQUA (-4425 3875);
DISPLAY INVISIBLE (-4425 3875);
FORCEPROP 2 LAST CDS_LIB mstr_discrete
J 0
(-3950 3875);
PAINT ORANGE (-3950 3875);
DISPLAY INVISIBLE (-3950 3875);
FORCEPROP 0 LAST BOM_COST ST_FLASH
J 0
(-3225 3975);
DISPLAY 1.021277 (-3225 3975);
PAINT ORANGE (-3225 3975);
DISPLAY INVISIBLE (-3225 3975);
FORCEPROP 0 LAST ROOM M_2
J 0
(-3225 3925);
DISPLAY 1.021277 (-3225 3925);
PAINT ORANGE (-3225 3925);
DISPLAY INVISIBLE (-3225 3925);
FORCEPROP 1 LAST PATH I65
J 0
(-3950 4075);
DISPLAY 0.978723 (-3950 4075);
PAINT WHITE (-3950 4075);
DISPLAY INVISIBLE (-3950 4075);
FORCEPROP 2 LAST SEC_TYPE 0402
J 0
(-3950 4125);
DISPLAY 1.021277 (-3950 4125);
PAINT ORANGE (-3950 4125);
DISPLAY INVISIBLE (-3950 4125);
FORCEPROP 2 LAST SEC 1
J 0
(-3950 4125);
DISPLAY 0.680851 (-3950 4125);
PAINT MONO (-3950 4125);
DISPLAY INVISIBLE (-3950 4125);
FORCEADD CAP..2
(-3950 4175);
FORCEPROP 1 LAST VALUE 0.22UF
J 2
(-4175 4175);
DISPLAY 0.617021 (-4175 4175);
PAINT SKYBLUE (-4175 4175);
FORCEPROP 1 LAST LOCATION C2T20
J 1
(-4425 4175);
DISPLAY 0.617021 (-4425 4175);
PAINT AQUA (-4425 4175);
FORCEPROP 1 LAST TOLERANCE 10%
J 2
(-4075 4175);
DISPLAY 0.617021 (-4075 4175);
PAINT SKYBLUE (-4075 4175);
FORCEPROP 1 LASTPIN (-4050 4175) $PN 1
J 0
(-4060 4190);
DISPLAY 0.617021 (-4060 4190);
PAINT ORANGE (-4060 4190);
FORCEPROP 1 LASTPIN (-3850 4175) $PN 2
J 0
(-3865 4190);
DISPLAY 0.617021 (-3865 4190);
PAINT ORANGE (-3865 4190);
FORCEPROP 1 LAST MATERIAL X7R
J 0
(-3800 4175);
DISPLAY 0.617021 (-3800 4175);
PAINT SKYBLUE (-3800 4175);
FORCEPROP 1 LAST VOLTAGE 16V
J 0
(-3675 4175);
DISPLAY 0.617021 (-3675 4175);
PAINT SKYBLUE (-3675 4175);
FORCEPROP 1 LAST PACK_TYPE 0402
J 1
(-3525 4175);
DISPLAY 0.617021 (-3525 4175);
PAINT SKYBLUE (-3525 4175);
FORCEPROP 1 LAST PART_NUMBER A36096-155
J 2
(-3225 4175);
DISPLAY 0.617021 (-3225 4175);
PAINT BLUE (-3225 4175);
FORCEPROP 2 LAST CDS_LOCATION C2T20
J 1
(-4425 4175);
DISPLAY 0.617021 (-4425 4175);
PAINT AQUA (-4425 4175);
DISPLAY INVISIBLE (-4425 4175);
FORCEPROP 2 LAST CDS_LIB mstr_discrete
J 0
(-3950 4175);
PAINT ORANGE (-3950 4175);
DISPLAY INVISIBLE (-3950 4175);
FORCEPROP 1 LAST PATH I66
J 0
(-3950 4375);
DISPLAY 0.978723 (-3950 4375);
PAINT WHITE (-3950 4375);
DISPLAY INVISIBLE (-3950 4375);
FORCEPROP 2 LAST SEC_TYPE 0402
J 0
(-3950 4425);
DISPLAY 1.021277 (-3950 4425);
PAINT ORANGE (-3950 4425);
DISPLAY INVISIBLE (-3950 4425);
FORCEPROP 2 LAST SEC 1
J 0
(-3950 4425);
DISPLAY 0.680851 (-3950 4425);
PAINT MONO (-3950 4425);
DISPLAY INVISIBLE (-3950 4425);
FORCEPROP 0 LAST ROOM M_2
J 0
(-3225 4225);
DISPLAY 1.021277 (-3225 4225);
PAINT ORANGE (-3225 4225);
DISPLAY INVISIBLE (-3225 4225);
FORCEPROP 0 LAST BOM_COST ST_FLASH
J 0
(-3225 4275);
DISPLAY 1.021277 (-3225 4275);
PAINT ORANGE (-3225 4275);
DISPLAY INVISIBLE (-3225 4275);
FORCEADD CAP..2
(-3950 4125);
FORCEPROP 1 LAST VALUE 0.22UF
J 2
(-4175 4125);
DISPLAY 0.617021 (-4175 4125);
PAINT SKYBLUE (-4175 4125);
FORCEPROP 1 LAST LOCATION C2T23
J 1
(-4425 4125);
DISPLAY 0.617021 (-4425 4125);
PAINT AQUA (-4425 4125);
FORCEPROP 1 LAST TOLERANCE 10%
J 2
(-4075 4125);
DISPLAY 0.617021 (-4075 4125);
PAINT SKYBLUE (-4075 4125);
FORCEPROP 1 LASTPIN (-4050 4125) $PN 1
J 0
(-4060 4140);
DISPLAY 0.617021 (-4060 4140);
PAINT ORANGE (-4060 4140);
FORCEPROP 1 LASTPIN (-3850 4125) $PN 2
J 0
(-3865 4140);
DISPLAY 0.617021 (-3865 4140);
PAINT ORANGE (-3865 4140);
FORCEPROP 1 LAST MATERIAL X7R
J 0
(-3800 4125);
DISPLAY 0.617021 (-3800 4125);
PAINT SKYBLUE (-3800 4125);
FORCEPROP 1 LAST VOLTAGE 16V
J 0
(-3675 4125);
DISPLAY 0.617021 (-3675 4125);
PAINT SKYBLUE (-3675 4125);
FORCEPROP 1 LAST PACK_TYPE 0402
J 1
(-3525 4125);
DISPLAY 0.617021 (-3525 4125);
PAINT SKYBLUE (-3525 4125);
FORCEPROP 1 LAST PART_NUMBER A36096-155
J 2
(-3225 4125);
DISPLAY 0.617021 (-3225 4125);
PAINT BLUE (-3225 4125);
FORCEPROP 2 LAST CDS_LOCATION C2T23
J 1
(-4425 4125);
DISPLAY 0.617021 (-4425 4125);
PAINT AQUA (-4425 4125);
DISPLAY INVISIBLE (-4425 4125);
FORCEPROP 2 LAST CDS_LIB mstr_discrete
J 0
(-3950 4125);
PAINT ORANGE (-3950 4125);
DISPLAY INVISIBLE (-3950 4125);
FORCEPROP 1 LAST PATH I67
J 0
(-3950 4325);
DISPLAY 0.978723 (-3950 4325);
PAINT WHITE (-3950 4325);
DISPLAY INVISIBLE (-3950 4325);
FORCEPROP 2 LAST SEC 1
J 0
(-3950 4375);
DISPLAY 0.680851 (-3950 4375);
PAINT MONO (-3950 4375);
DISPLAY INVISIBLE (-3950 4375);
FORCEPROP 2 LAST SEC_TYPE 0402
J 0
(-3950 4375);
DISPLAY 1.021277 (-3950 4375);
PAINT ORANGE (-3950 4375);
DISPLAY INVISIBLE (-3950 4375);
FORCEPROP 0 LAST ROOM M_2
J 0
(-3225 4175);
DISPLAY 1.021277 (-3225 4175);
PAINT ORANGE (-3225 4175);
DISPLAY INVISIBLE (-3225 4175);
FORCEPROP 0 LAST BOM_COST ST_FLASH
J 0
(-3225 4225);
DISPLAY 1.021277 (-3225 4225);
PAINT ORANGE (-3225 4225);
DISPLAY INVISIBLE (-3225 4225);
FORCEADD OFFPAGE..2
(-2600 4275);
FORCEPROP 2 LAST $XR0 116 
J 0
(-2411 4275);
DISPLAY 0.638298 (-2411 4275);
PAINT MONO (-2411 4275);
FORCEPROP 1 LAST COMMENT_BODY TRUE
J 0
(-2645 4180);
DISPLAY 0.872340 (-2645 4180);
PAINT GREEN (-2645 4180);
DISPLAY INVISIBLE (-2645 4180);
FORCEPROP 2 LAST CDS_LIB mstr_standard
J 0
(-2600 4275);
PAINT ORANGE (-2600 4275);
DISPLAY INVISIBLE (-2600 4275);
FORCEPROP 2 LAST PATH I68
J 0
(-2425 4350);
DISPLAY 1.021277 (-2425 4350);
PAINT ORANGE (-2425 4350);
DISPLAY INVISIBLE (-2425 4350);
FORCEPROP 1 LAST OFFPAGE TRUE
J 0
(-2275 4150);
DISPLAY 0.872340 (-2275 4150);
PAINT GREEN (-2275 4150);
DISPLAY INVISIBLE (-2275 4150);
FORCEADD OFFPAGE..2
(-2600 4225);
FORCEPROP 2 LAST $XR0 116 
J 0
(-2411 4225);
DISPLAY 0.638298 (-2411 4225);
PAINT MONO (-2411 4225);
FORCEPROP 1 LAST COMMENT_BODY TRUE
J 0
(-2645 4130);
DISPLAY 0.872340 (-2645 4130);
PAINT GREEN (-2645 4130);
DISPLAY INVISIBLE (-2645 4130);
FORCEPROP 2 LAST CDS_LIB mstr_standard
J 0
(-2600 4225);
PAINT ORANGE (-2600 4225);
DISPLAY INVISIBLE (-2600 4225);
FORCEPROP 2 LAST PATH I69
J 0
(-2425 4300);
DISPLAY 1.021277 (-2425 4300);
PAINT ORANGE (-2425 4300);
DISPLAY INVISIBLE (-2425 4300);
FORCEPROP 1 LAST OFFPAGE TRUE
J 0
(-2275 4100);
DISPLAY 0.872340 (-2275 4100);
PAINT GREEN (-2275 4100);
DISPLAY INVISIBLE (-2275 4100);
FORCEADD OFFPAGE..4
(-2600 4175);
FORCEPROP 2 LAST $XR0 116 
J 0
(-2414 4175);
DISPLAY 0.638298 (-2414 4175);
PAINT MONO (-2414 4175);
FORCEPROP 1 LAST OFFPAGE TRUE
J 0
(-2275 4050);
DISPLAY 0.872340 (-2275 4050);
PAINT GREEN (-2275 4050);
DISPLAY INVISIBLE (-2275 4050);
FORCEPROP 1 LAST COMMENT_BODY TRUE
J 0
(-2625 4075);
DISPLAY 0.872340 (-2625 4075);
PAINT GREEN (-2625 4075);
DISPLAY INVISIBLE (-2625 4075);
FORCEPROP 2 LAST CDS_LIB mstr_standard
J 0
(-2600 4175);
PAINT ORANGE (-2600 4175);
DISPLAY INVISIBLE (-2600 4175);
FORCEPROP 2 LAST PATH I70
J 0
(-2425 4250);
DISPLAY 1.021277 (-2425 4250);
PAINT ORANGE (-2425 4250);
DISPLAY INVISIBLE (-2425 4250);
FORCEADD OFFPAGE..4
(-2600 4125);
FORCEPROP 2 LAST $XR0 116 
J 0
(-2414 4125);
DISPLAY 0.638298 (-2414 4125);
PAINT MONO (-2414 4125);
FORCEPROP 1 LAST COMMENT_BODY TRUE
J 0
(-2625 4025);
DISPLAY 0.872340 (-2625 4025);
PAINT GREEN (-2625 4025);
DISPLAY INVISIBLE (-2625 4025);
FORCEPROP 1 LAST OFFPAGE TRUE
J 0
(-2275 4000);
DISPLAY 0.872340 (-2275 4000);
PAINT GREEN (-2275 4000);
DISPLAY INVISIBLE (-2275 4000);
FORCEPROP 2 LAST CDS_LIB mstr_standard
J 0
(-2600 4125);
PAINT ORANGE (-2600 4125);
DISPLAY INVISIBLE (-2600 4125);
FORCEPROP 2 LAST PATH I71
J 0
(-2425 4200);
DISPLAY 1.021277 (-2425 4200);
PAINT ORANGE (-2425 4200);
DISPLAY INVISIBLE (-2425 4200);
FORCEADD OFFPAGE..2
(-2600 4025);
FORCEPROP 2 LAST $XR0 116 
J 0
(-2411 4025);
DISPLAY 0.638298 (-2411 4025);
PAINT MONO (-2411 4025);
FORCEPROP 1 LAST COMMENT_BODY TRUE
J 0
(-2645 3930);
DISPLAY 0.872340 (-2645 3930);
PAINT GREEN (-2645 3930);
DISPLAY INVISIBLE (-2645 3930);
FORCEPROP 2 LAST CDS_LIB mstr_standard
J 0
(-2600 4025);
PAINT ORANGE (-2600 4025);
DISPLAY INVISIBLE (-2600 4025);
FORCEPROP 1 LAST OFFPAGE TRUE
J 0
(-2275 3900);
DISPLAY 0.872340 (-2275 3900);
PAINT GREEN (-2275 3900);
DISPLAY INVISIBLE (-2275 3900);
FORCEPROP 2 LAST PATH I72
J 0
(-2425 4100);
DISPLAY 1.021277 (-2425 4100);
PAINT ORANGE (-2425 4100);
DISPLAY INVISIBLE (-2425 4100);
FORCEADD OFFPAGE..2
(-2600 3975);
FORCEPROP 2 LAST $XR0 116 
J 0
(-2411 3975);
DISPLAY 0.638298 (-2411 3975);
PAINT MONO (-2411 3975);
FORCEPROP 1 LAST COMMENT_BODY TRUE
J 0
(-2645 3880);
DISPLAY 0.872340 (-2645 3880);
PAINT GREEN (-2645 3880);
DISPLAY INVISIBLE (-2645 3880);
FORCEPROP 2 LAST CDS_LIB mstr_standard
J 0
(-2600 3975);
PAINT ORANGE (-2600 3975);
DISPLAY INVISIBLE (-2600 3975);
FORCEPROP 2 LAST PATH I73
J 0
(-2425 4050);
DISPLAY 1.021277 (-2425 4050);
PAINT ORANGE (-2425 4050);
DISPLAY INVISIBLE (-2425 4050);
FORCEPROP 1 LAST OFFPAGE TRUE
J 0
(-2275 3850);
DISPLAY 0.872340 (-2275 3850);
PAINT GREEN (-2275 3850);
DISPLAY INVISIBLE (-2275 3850);
FORCEADD OFFPAGE..4
(-2600 3925);
FORCEPROP 2 LAST $XR0 116 
J 0
(-2414 3925);
DISPLAY 0.638298 (-2414 3925);
PAINT MONO (-2414 3925);
FORCEPROP 1 LAST COMMENT_BODY TRUE
J 0
(-2625 3825);
DISPLAY 0.872340 (-2625 3825);
PAINT GREEN (-2625 3825);
DISPLAY INVISIBLE (-2625 3825);
FORCEPROP 2 LAST CDS_LIB mstr_standard
J 0
(-2600 3925);
PAINT ORANGE (-2600 3925);
DISPLAY INVISIBLE (-2600 3925);
FORCEPROP 2 LAST PATH I74
J 0
(-2425 4000);
DISPLAY 1.021277 (-2425 4000);
PAINT ORANGE (-2425 4000);
DISPLAY INVISIBLE (-2425 4000);
FORCEPROP 1 LAST OFFPAGE TRUE
J 0
(-2275 3800);
DISPLAY 0.872340 (-2275 3800);
PAINT GREEN (-2275 3800);
DISPLAY INVISIBLE (-2275 3800);
FORCEADD OFFPAGE..4
(-2600 3875);
FORCEPROP 2 LAST $XR0 116 
J 0
(-2414 3875);
DISPLAY 0.638298 (-2414 3875);
PAINT MONO (-2414 3875);
FORCEPROP 1 LAST COMMENT_BODY TRUE
J 0
(-2625 3775);
DISPLAY 0.872340 (-2625 3775);
PAINT GREEN (-2625 3775);
DISPLAY INVISIBLE (-2625 3775);
FORCEPROP 2 LAST CDS_LIB mstr_standard
J 0
(-2600 3875);
PAINT ORANGE (-2600 3875);
DISPLAY INVISIBLE (-2600 3875);
FORCEPROP 2 LAST PATH I75
J 0
(-2425 3950);
DISPLAY 1.021277 (-2425 3950);
PAINT ORANGE (-2425 3950);
DISPLAY INVISIBLE (-2425 3950);
FORCEPROP 1 LAST OFFPAGE TRUE
J 0
(-2275 3750);
DISPLAY 0.872340 (-2275 3750);
PAINT GREEN (-2275 3750);
DISPLAY INVISIBLE (-2275 3750);
FORCEADD OFFPAGE..4
(-2600 3625);
FORCEPROP 2 LAST $XR0 116 
J 0
(-2414 3625);
DISPLAY 0.638298 (-2414 3625);
PAINT MONO (-2414 3625);
FORCEPROP 1 LAST COMMENT_BODY TRUE
J 0
(-2625 3525);
DISPLAY 0.872340 (-2625 3525);
PAINT GREEN (-2625 3525);
DISPLAY INVISIBLE (-2625 3525);
FORCEPROP 2 LAST CDS_LIB mstr_standard
J 0
(-2600 3625);
PAINT ORANGE (-2600 3625);
DISPLAY INVISIBLE (-2600 3625);
FORCEPROP 1 LAST OFFPAGE TRUE
J 0
(-2275 3500);
DISPLAY 0.872340 (-2275 3500);
PAINT GREEN (-2275 3500);
DISPLAY INVISIBLE (-2275 3500);
FORCEPROP 2 LAST PATH I76
J 0
(-2425 3700);
DISPLAY 1.021277 (-2425 3700);
PAINT ORANGE (-2425 3700);
DISPLAY INVISIBLE (-2425 3700);
FORCEADD OFFPAGE..4
(-2600 3675);
FORCEPROP 2 LAST $XR0 116 
J 0
(-2414 3675);
DISPLAY 0.638298 (-2414 3675);
PAINT MONO (-2414 3675);
FORCEPROP 1 LAST COMMENT_BODY TRUE
J 0
(-2625 3575);
DISPLAY 0.872340 (-2625 3575);
PAINT GREEN (-2625 3575);
DISPLAY INVISIBLE (-2625 3575);
FORCEPROP 2 LAST CDS_LIB mstr_standard
J 0
(-2600 3675);
PAINT ORANGE (-2600 3675);
DISPLAY INVISIBLE (-2600 3675);
FORCEPROP 1 LAST OFFPAGE TRUE
J 0
(-2275 3550);
DISPLAY 0.872340 (-2275 3550);
PAINT GREEN (-2275 3550);
DISPLAY INVISIBLE (-2275 3550);
FORCEPROP 2 LAST PATH I77
J 0
(-2425 3750);
DISPLAY 1.021277 (-2425 3750);
PAINT ORANGE (-2425 3750);
DISPLAY INVISIBLE (-2425 3750);
FORCEADD OFFPAGE..2
(-2600 3775);
FORCEPROP 2 LAST $XR0 116 
J 0
(-2411 3775);
DISPLAY 0.638298 (-2411 3775);
PAINT MONO (-2411 3775);
FORCEPROP 1 LAST COMMENT_BODY TRUE
J 0
(-2645 3680);
DISPLAY 0.872340 (-2645 3680);
PAINT GREEN (-2645 3680);
DISPLAY INVISIBLE (-2645 3680);
FORCEPROP 2 LAST CDS_LIB mstr_standard
J 0
(-2600 3775);
PAINT ORANGE (-2600 3775);
DISPLAY INVISIBLE (-2600 3775);
FORCEPROP 2 LAST PATH I78
J 0
(-2425 3850);
DISPLAY 1.021277 (-2425 3850);
PAINT ORANGE (-2425 3850);
DISPLAY INVISIBLE (-2425 3850);
FORCEPROP 1 LAST OFFPAGE TRUE
J 0
(-2275 3650);
DISPLAY 0.872340 (-2275 3650);
PAINT GREEN (-2275 3650);
DISPLAY INVISIBLE (-2275 3650);
FORCEADD OFFPAGE..2
(-2600 3725);
FORCEPROP 2 LAST $XR0 116 
J 0
(-2411 3725);
DISPLAY 0.638298 (-2411 3725);
PAINT MONO (-2411 3725);
FORCEPROP 1 LAST COMMENT_BODY TRUE
J 0
(-2645 3630);
DISPLAY 0.872340 (-2645 3630);
PAINT GREEN (-2645 3630);
DISPLAY INVISIBLE (-2645 3630);
FORCEPROP 2 LAST CDS_LIB mstr_standard
J 0
(-2600 3725);
PAINT ORANGE (-2600 3725);
DISPLAY INVISIBLE (-2600 3725);
FORCEPROP 2 LAST PATH I79
J 0
(-2425 3800);
DISPLAY 1.021277 (-2425 3800);
PAINT ORANGE (-2425 3800);
DISPLAY INVISIBLE (-2425 3800);
FORCEPROP 1 LAST OFFPAGE TRUE
J 0
(-2275 3600);
DISPLAY 0.872340 (-2275 3600);
PAINT GREEN (-2275 3600);
DISPLAY INVISIBLE (-2275 3600);
FORCEADD OFFPAGE..1
(-7675 3475);
FORCEPROP 2 LAST $XR0 185 
J 0
(-7927 3475);
DISPLAY 0.638298 (-7927 3475);
PAINT MONO (-7927 3475);
FORCEPROP 2 LASTPIN (-7625 3475) SIG_NAME P3E_PCH_M2_SATA6G_TX_R_DN
J 0
(-7625 3485);
DISPLAY 0.617021 (-7625 3485);
PAINT ORANGE (-7625 3485);
FORCEPROP 2 LAST CDS_LIB mstr_standard
J 0
(-7675 3475);
PAINT ORANGE (-7675 3475);
DISPLAY INVISIBLE (-7675 3475);
FORCEPROP 1 LAST COMMENT_BODY TRUE
J 0
(-7550 3375);
DISPLAY 0.872340 (-7550 3375);
PAINT GREEN (-7550 3375);
DISPLAY INVISIBLE (-7550 3375);
FORCEPROP 1 LAST OFFPAGE TRUE
J 0
(-7350 3350);
DISPLAY 0.872340 (-7350 3350);
PAINT GREEN (-7350 3350);
DISPLAY INVISIBLE (-7350 3350);
FORCEPROP 2 LAST PATH I80
J 0
(-7625 3550);
DISPLAY 1.021277 (-7625 3550);
PAINT ORANGE (-7625 3550);
DISPLAY INVISIBLE (-7625 3550);
FORCEADD OFFPAGE..1
(-7675 3525);
FORCEPROP 2 LAST $XR0 185 
J 0
(-7927 3525);
DISPLAY 0.638298 (-7927 3525);
PAINT MONO (-7927 3525);
FORCEPROP 2 LAST CDS_LIB mstr_standard
J 0
(-7675 3525);
PAINT ORANGE (-7675 3525);
DISPLAY INVISIBLE (-7675 3525);
FORCEPROP 1 LAST COMMENT_BODY TRUE
J 0
(-7550 3425);
DISPLAY 0.872340 (-7550 3425);
PAINT GREEN (-7550 3425);
DISPLAY INVISIBLE (-7550 3425);
FORCEPROP 1 LAST OFFPAGE TRUE
J 0
(-7350 3400);
DISPLAY 0.872340 (-7350 3400);
PAINT GREEN (-7350 3400);
DISPLAY INVISIBLE (-7350 3400);
FORCEPROP 2 LAST PATH I81
J 0
(-7625 3600);
DISPLAY 1.021277 (-7625 3600);
PAINT ORANGE (-7625 3600);
DISPLAY INVISIBLE (-7625 3600);
FORCEADD OFFPAGE..5
(-7675 3725);
FORCEPROP 2 LAST $XR0 185 
J 0
(-7930 3725);
DISPLAY 0.638298 (-7930 3725);
PAINT MONO (-7930 3725);
FORCEPROP 1 LAST COMMENT_BODY TRUE
J 0
(-7575 3650);
DISPLAY 0.872340 (-7575 3650);
PAINT GREEN (-7575 3650);
DISPLAY INVISIBLE (-7575 3650);
FORCEPROP 2 LAST CDS_LIB mstr_standard
J 0
(-7675 3725);
PAINT ORANGE (-7675 3725);
DISPLAY INVISIBLE (-7675 3725);
FORCEPROP 2 LAST PATH I82
J 0
(-7625 3800);
DISPLAY 1.021277 (-7625 3800);
PAINT ORANGE (-7625 3800);
DISPLAY INVISIBLE (-7625 3800);
FORCEPROP 1 LAST OFFPAGE TRUE
J 0
(-7350 3600);
DISPLAY 0.872340 (-7350 3600);
PAINT GREEN (-7350 3600);
DISPLAY INVISIBLE (-7350 3600);
FORCEADD OFFPAGE..5
(-7675 3675);
FORCEPROP 2 LAST $XR0 185 
J 0
(-7930 3675);
DISPLAY 0.638298 (-7930 3675);
PAINT MONO (-7930 3675);
FORCEPROP 1 LAST OFFPAGE TRUE
J 0
(-7350 3550);
DISPLAY 0.872340 (-7350 3550);
PAINT GREEN (-7350 3550);
DISPLAY INVISIBLE (-7350 3550);
FORCEPROP 1 LAST COMMENT_BODY TRUE
J 0
(-7575 3600);
DISPLAY 0.872340 (-7575 3600);
PAINT GREEN (-7575 3600);
DISPLAY INVISIBLE (-7575 3600);
FORCEPROP 2 LAST CDS_LIB mstr_standard
J 0
(-7675 3675);
PAINT ORANGE (-7675 3675);
DISPLAY INVISIBLE (-7675 3675);
FORCEPROP 2 LAST PATH I83
J 0
(-7625 3750);
DISPLAY 1.021277 (-7625 3750);
PAINT ORANGE (-7625 3750);
DISPLAY INVISIBLE (-7625 3750);
FORCEADD OFFPAGE..4
(-4400 3075);
FORCEPROP 2 LAST $XR0 114 
J 0
(-4214 3075);
DISPLAY 0.638298 (-4214 3075);
PAINT MONO (-4214 3075);
FORCEPROP 1 LAST COMMENT_BODY TRUE
J 0
(-4425 2975);
DISPLAY 0.872340 (-4425 2975);
PAINT GREEN (-4425 2975);
DISPLAY INVISIBLE (-4425 2975);
FORCEPROP 2 LAST CDS_LIB mstr_standard
J 0
(-4400 3075);
PAINT ORANGE (-4400 3075);
DISPLAY INVISIBLE (-4400 3075);
FORCEPROP 2 LAST PATH I85
J 0
(-4225 3150);
DISPLAY 1.021277 (-4225 3150);
PAINT ORANGE (-4225 3150);
DISPLAY INVISIBLE (-4225 3150);
FORCEPROP 1 LAST OFFPAGE TRUE
J 0
(-4075 2950);
DISPLAY 0.872340 (-4075 2950);
PAINT GREEN (-4075 2950);
DISPLAY INVISIBLE (-4075 2950);
FORCEADD OFFPAGE..4
(-4400 3025);
FORCEPROP 2 LAST $XR0 114 
J 0
(-4214 3025);
DISPLAY 0.638298 (-4214 3025);
PAINT MONO (-4214 3025);
FORCEPROP 1 LAST COMMENT_BODY TRUE
J 0
(-4425 2925);
DISPLAY 0.872340 (-4425 2925);
PAINT GREEN (-4425 2925);
DISPLAY INVISIBLE (-4425 2925);
FORCEPROP 2 LAST CDS_LIB mstr_standard
J 0
(-4400 3025);
PAINT ORANGE (-4400 3025);
DISPLAY INVISIBLE (-4400 3025);
FORCEPROP 2 LAST PATH I86
J 0
(-4225 3100);
DISPLAY 1.021277 (-4225 3100);
PAINT ORANGE (-4225 3100);
DISPLAY INVISIBLE (-4225 3100);
FORCEPROP 1 LAST OFFPAGE TRUE
J 0
(-4075 2900);
DISPLAY 0.872340 (-4075 2900);
PAINT GREEN (-4075 2900);
DISPLAY INVISIBLE (-4075 2900);
FORCEADD OFFPAGE..4
(-4400 3325);
FORCEPROP 2 LAST $XR0 190 
J 0
(-4214 3325);
DISPLAY 0.638298 (-4214 3325);
PAINT MONO (-4214 3325);
FORCEPROP 1 LAST COMMENT_BODY TRUE
J 0
(-4425 3225);
DISPLAY 0.872340 (-4425 3225);
PAINT GREEN (-4425 3225);
DISPLAY INVISIBLE (-4425 3225);
FORCEPROP 2 LAST CDS_LIB mstr_standard
J 0
(-4400 3325);
PAINT ORANGE (-4400 3325);
DISPLAY INVISIBLE (-4400 3325);
FORCEPROP 2 LAST PATH I87
J 0
(-4225 3400);
DISPLAY 1.021277 (-4225 3400);
PAINT ORANGE (-4225 3400);
DISPLAY INVISIBLE (-4225 3400);
FORCEPROP 1 LAST OFFPAGE TRUE
J 0
(-4075 3200);
DISPLAY 0.872340 (-4075 3200);
PAINT GREEN (-4075 3200);
DISPLAY INVISIBLE (-4075 3200);
FORCEADD OFFPAGE..2
(-4400 3175);
FORCEPROP 2 LAST $XR0 142 
J 0
(-4211 3175);
DISPLAY 0.638298 (-4211 3175);
PAINT MONO (-4211 3175);
FORCEPROP 1 LAST COMMENT_BODY TRUE
J 0
(-4445 3080);
DISPLAY 0.872340 (-4445 3080);
PAINT GREEN (-4445 3080);
DISPLAY INVISIBLE (-4445 3080);
FORCEPROP 2 LAST CDS_LIB mstr_standard
J 0
(-4400 3175);
PAINT ORANGE (-4400 3175);
DISPLAY INVISIBLE (-4400 3175);
FORCEPROP 2 LAST PATH I89
J 0
(-4225 3250);
DISPLAY 1.021277 (-4225 3250);
PAINT ORANGE (-4225 3250);
DISPLAY INVISIBLE (-4225 3250);
FORCEPROP 1 LAST OFFPAGE TRUE
J 0
(-4075 3050);
DISPLAY 0.872340 (-4075 3050);
PAINT GREEN (-4075 3050);
DISPLAY INVISIBLE (-4075 3050);
FORCEADD CAP_A..2
(-2875 850);
FORCEPROP 1 LAST LOCATION C8F15
J 0
(-3375 850);
DISPLAY 0.617021 (-3375 850);
PAINT AQUA (-3375 850);
FORCEPROP 1 LAST TOLERANCE 10%
J 2
(-3025 750);
DISPLAY 0.617021 (-3025 750);
PAINT SKYBLUE (-3025 750);
FORCEPROP 1 LAST VALUE 0.01UF
J 2
(-3000 800);
DISPLAY 0.617021 (-3000 800);
PAINT SKYBLUE (-3000 800);
FORCEPROP 1 LAST PACK_TYPE 0402V
J 1
(-2875 500);
DISPLAY 0.617021 (-2875 500);
PAINT SKYBLUE (-2875 500);
FORCEPROP 1 LAST MATERIAL EMPTY
J 0
(-2875 700);
DISPLAY 0.617021 (-2875 700);
PAINT RED (-2875 700);
FORCEPROP 1 LAST VOLTAGE 25V
J 0
(-2700 800);
DISPLAY 0.617021 (-2700 800);
PAINT SKYBLUE (-2700 800);
FORCEPROP 1 LAST PART_NUMBER A36096-045
J 1
(-2475 875);
DISPLAY 0.617021 (-2475 875);
PAINT BLUE (-2475 875);
FORCEPROP 2 LAST CDS_LOCATION C8F15
J 0
(-3375 850);
DISPLAY 0.617021 (-3375 850);
PAINT AQUA (-3375 850);
DISPLAY INVISIBLE (-3375 850);
FORCEPROP 1 LASTPIN (-2975 850) $PN 1
J 0
(-2985 865);
DISPLAY 0.787234 (-2985 865);
PAINT ORANGE (-2985 865);
DISPLAY INVISIBLE (-2985 865);
FORCEPROP 2 LAST CDS_LIB dev_discrete
J 0
(-2875 850);
PAINT ORANGE (-2875 850);
DISPLAY INVISIBLE (-2875 850);
FORCEPROP 1 LASTPIN (-2775 850) $PN 2
J 0
(-2790 865);
DISPLAY 0.787234 (-2790 865);
PAINT ORANGE (-2790 865);
DISPLAY INVISIBLE (-2790 865);
FORCEPROP 0 LAST BOM_COST ST_FLASH
J 0
(-2125 950);
DISPLAY 1.021277 (-2125 950);
PAINT ORANGE (-2125 950);
DISPLAY INVISIBLE (-2125 950);
FORCEPROP 0 LAST ROOM M_2
J 0
(-2125 900);
DISPLAY 1.021277 (-2125 900);
PAINT ORANGE (-2125 900);
DISPLAY INVISIBLE (-2125 900);
FORCEPROP 1 LAST PATH I90
J 0
(-2875 1050);
DISPLAY 0.978723 (-2875 1050);
PAINT WHITE (-2875 1050);
DISPLAY INVISIBLE (-2875 1050);
FORCEPROP 2 LAST NO_XNET_CONNECTION 1
J 0
(-2875 1100);
PAINT MONO (-2875 1100);
DISPLAY INVISIBLE (-2875 1100);
FORCEADD OFFPAGE..2
(-1450 2200);
FORCEPROP 2 LAST $XR0 185 
J 0
(-1261 2200);
DISPLAY 0.638298 (-1261 2200);
PAINT MONO (-1261 2200);
FORCEPROP 1 LAST COMMENT_BODY TRUE
J 0
(-1495 2105);
DISPLAY 0.872340 (-1495 2105);
PAINT GREEN (-1495 2105);
DISPLAY INVISIBLE (-1495 2105);
FORCEPROP 2 LAST CDS_LIB mstr_standard
J 0
(-1450 2200);
PAINT ORANGE (-1450 2200);
DISPLAY INVISIBLE (-1450 2200);
FORCEPROP 2 LAST PATH I91
J 0
(-1250 2250);
DISPLAY 1.021277 (-1250 2250);
PAINT ORANGE (-1250 2250);
DISPLAY INVISIBLE (-1250 2250);
FORCEPROP 1 LAST OFFPAGE TRUE
J 0
(-1125 2075);
DISPLAY 0.872340 (-1125 2075);
PAINT GREEN (-1125 2075);
DISPLAY INVISIBLE (-1125 2075);
FORCEADD OFFPAGE..2
(-1450 1700);
FORCEPROP 2 LAST $XR0 185 
J 0
(-1261 1700);
DISPLAY 0.638298 (-1261 1700);
PAINT MONO (-1261 1700);
FORCEPROP 1 LAST COMMENT_BODY TRUE
J 0
(-1495 1605);
DISPLAY 0.872340 (-1495 1605);
PAINT GREEN (-1495 1605);
DISPLAY INVISIBLE (-1495 1605);
FORCEPROP 2 LAST CDS_LIB mstr_standard
J 0
(-1450 1700);
PAINT ORANGE (-1450 1700);
DISPLAY INVISIBLE (-1450 1700);
FORCEPROP 2 LAST PATH I92
J 0
(-1250 1750);
DISPLAY 1.021277 (-1250 1750);
PAINT ORANGE (-1250 1750);
DISPLAY INVISIBLE (-1250 1750);
FORCEPROP 1 LAST OFFPAGE TRUE
J 0
(-1125 1575);
DISPLAY 0.872340 (-1125 1575);
PAINT GREEN (-1125 1575);
DISPLAY INVISIBLE (-1125 1575);
FORCEADD OFFPAGE..4
(-1450 1275);
FORCEPROP 2 LAST $XR0 185 
J 0
(-1264 1275);
DISPLAY 0.638298 (-1264 1275);
PAINT MONO (-1264 1275);
FORCEPROP 1 LAST COMMENT_BODY TRUE
J 0
(-1475 1175);
DISPLAY 0.872340 (-1475 1175);
PAINT GREEN (-1475 1175);
DISPLAY INVISIBLE (-1475 1175);
FORCEPROP 2 LAST CDS_LIB mstr_standard
J 0
(-1450 1275);
PAINT ORANGE (-1450 1275);
DISPLAY INVISIBLE (-1450 1275);
FORCEPROP 2 LAST PATH I93
J 0
(-1250 1325);
DISPLAY 1.021277 (-1250 1325);
PAINT ORANGE (-1250 1325);
DISPLAY INVISIBLE (-1250 1325);
FORCEPROP 1 LAST OFFPAGE TRUE
J 0
(-1125 1150);
DISPLAY 0.872340 (-1125 1150);
PAINT GREEN (-1125 1150);
DISPLAY INVISIBLE (-1125 1150);
FORCEADD OFFPAGE..4
(-1450 850);
FORCEPROP 2 LAST $XR0 185 
J 0
(-1264 850);
DISPLAY 0.638298 (-1264 850);
PAINT MONO (-1264 850);
FORCEPROP 1 LAST COMMENT_BODY TRUE
J 0
(-1475 750);
DISPLAY 0.872340 (-1475 750);
PAINT GREEN (-1475 750);
DISPLAY INVISIBLE (-1475 750);
FORCEPROP 2 LAST CDS_LIB mstr_standard
J 0
(-1450 850);
PAINT ORANGE (-1450 850);
DISPLAY INVISIBLE (-1450 850);
FORCEPROP 2 LAST PATH I94
J 0
(-1250 900);
DISPLAY 1.021277 (-1250 900);
PAINT ORANGE (-1250 900);
DISPLAY INVISIBLE (-1250 900);
FORCEPROP 1 LAST OFFPAGE TRUE
J 0
(-1125 725);
DISPLAY 0.872340 (-1125 725);
PAINT GREEN (-1125 725);
DISPLAY INVISIBLE (-1125 725);
FORCEADD CAP_A..2
(-2900 2200);
FORCEPROP 1 LAST TOLERANCE 10%
J 2
(-3075 2100);
DISPLAY 0.617021 (-3075 2100);
PAINT SKYBLUE (-3075 2100);
FORCEPROP 1 LAST VALUE 0.01UF
J 2
(-3125 2150);
DISPLAY 0.617021 (-3125 2150);
PAINT SKYBLUE (-3125 2150);
FORCEPROP 1 LAST LOCATION C8F6
J 0
(-3400 2200);
DISPLAY 0.617021 (-3400 2200);
PAINT AQUA (-3400 2200);
FORCEPROP 1 LAST VOLTAGE 25V
J 0
(-3100 2150);
DISPLAY 0.617021 (-3100 2150);
PAINT SKYBLUE (-3100 2150);
FORCEPROP 1 LAST PACK_TYPE 0402V
J 1
(-2550 2150);
DISPLAY 0.617021 (-2550 2150);
PAINT SKYBLUE (-2550 2150);
FORCEPROP 1 LAST PART_NUMBER A36096-045
J 1
(-2575 2225);
DISPLAY 0.617021 (-2575 2225);
PAINT BLUE (-2575 2225);
FORCEPROP 1 LAST MATERIAL EMPTY
J 0
(-2625 2100);
DISPLAY 0.617021 (-2625 2100);
PAINT RED (-2625 2100);
FORCEPROP 2 LAST CDS_LOCATION C8F6
J 0
(-3400 2200);
DISPLAY 0.617021 (-3400 2200);
PAINT AQUA (-3400 2200);
DISPLAY INVISIBLE (-3400 2200);
FORCEPROP 1 LASTPIN (-3000 2200) $PN 1
J 0
(-3010 2215);
DISPLAY 0.787234 (-3010 2215);
PAINT ORANGE (-3010 2215);
DISPLAY INVISIBLE (-3010 2215);
FORCEPROP 2 LAST CDS_LIB dev_discrete
J 0
(-2900 2200);
PAINT ORANGE (-2900 2200);
DISPLAY INVISIBLE (-2900 2200);
FORCEPROP 1 LAST PATH I95
J 0
(-2900 2400);
DISPLAY 0.978723 (-2900 2400);
PAINT WHITE (-2900 2400);
DISPLAY INVISIBLE (-2900 2400);
FORCEPROP 2 LAST NO_XNET_CONNECTION 1
J 0
(-2900 2450);
PAINT MONO (-2900 2450);
DISPLAY INVISIBLE (-2900 2450);
FORCEPROP 1 LASTPIN (-2800 2200) $PN 2
J 0
(-2815 2215);
DISPLAY 0.787234 (-2815 2215);
PAINT ORANGE (-2815 2215);
DISPLAY INVISIBLE (-2815 2215);
FORCEPROP 0 LAST ROOM M_2
J 0
(-2150 2300);
DISPLAY 1.021277 (-2150 2300);
PAINT ORANGE (-2150 2300);
DISPLAY INVISIBLE (-2150 2300);
FORCEPROP 0 LAST BOM_COST ST_FLASH
J 0
(-2150 2250);
DISPLAY 1.021277 (-2150 2250);
PAINT ORANGE (-2150 2250);
DISPLAY INVISIBLE (-2150 2250);
FORCEADD CAP..2
(-2900 1925);
FORCEPROP 1 LAST LOCATION C8F7
J 0
(-3400 1925);
DISPLAY 0.617021 (-3400 1925);
PAINT AQUA (-3400 1925);
FORCEPROP 1 LAST VALUE 0.22UF
J 1
(-3175 1925);
DISPLAY 0.617021 (-3175 1925);
PAINT SKYBLUE (-3175 1925);
FORCEPROP 1 LAST TOLERANCE 10%
J 2
(-3025 1925);
DISPLAY 0.617021 (-3025 1925);
PAINT SKYBLUE (-3025 1925);
FORCEPROP 1 LASTPIN (-3000 1925) $PN 1
J 0
(-3010 1940);
DISPLAY 0.617021 (-3010 1940);
PAINT ORANGE (-3010 1940);
FORCEPROP 1 LAST VOLTAGE 16V
J 0
(-2650 1925);
DISPLAY 0.617021 (-2650 1925);
PAINT SKYBLUE (-2650 1925);
FORCEPROP 1 LAST MATERIAL X7R
J 0
(-2750 1925);
DISPLAY 0.617021 (-2750 1925);
PAINT SKYBLUE (-2750 1925);
FORCEPROP 1 LASTPIN (-2800 1925) $PN 2
J 0
(-2815 1940);
DISPLAY 0.617021 (-2815 1940);
PAINT ORANGE (-2815 1940);
FORCEPROP 1 LAST PART_NUMBER A36096-155
J 2
(-2150 1925);
DISPLAY 0.617021 (-2150 1925);
PAINT BLUE (-2150 1925);
FORCEPROP 1 LAST PACK_TYPE 0402
J 2
(-2425 1925);
DISPLAY 0.617021 (-2425 1925);
PAINT SKYBLUE (-2425 1925);
FORCEPROP 2 LAST CDS_LOCATION C8F7
J 0
(-3400 1925);
DISPLAY 0.617021 (-3400 1925);
PAINT AQUA (-3400 1925);
DISPLAY INVISIBLE (-3400 1925);
FORCEPROP 2 LAST CDS_LIB mstr_discrete
J 0
(-2900 1925);
PAINT ORANGE (-2900 1925);
DISPLAY INVISIBLE (-2900 1925);
FORCEPROP 0 LAST ROOM M_2
J 0
(-2150 1975);
DISPLAY 1.021277 (-2150 1975);
PAINT ORANGE (-2150 1975);
DISPLAY INVISIBLE (-2150 1975);
FORCEPROP 0 LAST BOM_COST ST_FLASH
J 0
(-2150 2025);
DISPLAY 1.021277 (-2150 2025);
PAINT ORANGE (-2150 2025);
DISPLAY INVISIBLE (-2150 2025);
FORCEPROP 1 LAST PATH I96
J 0
(-2900 2125);
DISPLAY 0.978723 (-2900 2125);
PAINT WHITE (-2900 2125);
DISPLAY INVISIBLE (-2900 2125);
FORCEPROP 2 LAST SEC_TYPE 0402
J 0
(-2900 2175);
DISPLAY 1.021277 (-2900 2175);
PAINT ORANGE (-2900 2175);
DISPLAY INVISIBLE (-2900 2175);
FORCEPROP 2 LAST SEC 1
J 0
(-2900 2175);
DISPLAY 0.680851 (-2900 2175);
PAINT MONO (-2900 2175);
DISPLAY INVISIBLE (-2900 2175);
FORCEADD CAP_A..2
(-2900 1700);
FORCEPROP 1 LAST MATERIAL EMPTY
J 0
(-3350 1600);
DISPLAY 0.617021 (-3350 1600);
PAINT RED (-3350 1600);
FORCEPROP 1 LAST LOCATION C8F11
J 0
(-3400 1700);
DISPLAY 0.617021 (-3400 1700);
PAINT AQUA (-3400 1700);
FORCEPROP 1 LAST TOLERANCE 10%
J 2
(-3100 1600);
DISPLAY 0.617021 (-3100 1600);
PAINT SKYBLUE (-3100 1600);
FORCEPROP 1 LAST VALUE 0.01UF
J 2
(-2950 1600);
DISPLAY 0.617021 (-2950 1600);
PAINT SKYBLUE (-2950 1600);
FORCEPROP 1 LAST VOLTAGE 25V
J 0
(-2750 1600);
DISPLAY 0.617021 (-2750 1600);
PAINT SKYBLUE (-2750 1600);
FORCEPROP 1 LAST PACK_TYPE 0402V
J 1
(-2525 1600);
DISPLAY 0.617021 (-2525 1600);
PAINT SKYBLUE (-2525 1600);
FORCEPROP 1 LAST PART_NUMBER A36096-045
J 1
(-2575 1725);
DISPLAY 0.617021 (-2575 1725);
PAINT BLUE (-2575 1725);
FORCEPROP 2 LAST CDS_LOCATION C8F11
J 0
(-3400 1700);
DISPLAY 0.617021 (-3400 1700);
PAINT AQUA (-3400 1700);
DISPLAY INVISIBLE (-3400 1700);
FORCEPROP 1 LASTPIN (-3000 1700) $PN 1
J 0
(-3010 1715);
DISPLAY 0.787234 (-3010 1715);
PAINT ORANGE (-3010 1715);
DISPLAY INVISIBLE (-3010 1715);
FORCEPROP 2 LAST CDS_LIB dev_discrete
J 0
(-2900 1700);
PAINT ORANGE (-2900 1700);
DISPLAY INVISIBLE (-2900 1700);
FORCEPROP 1 LAST PATH I97
J 0
(-2900 1900);
DISPLAY 0.978723 (-2900 1900);
PAINT WHITE (-2900 1900);
DISPLAY INVISIBLE (-2900 1900);
FORCEPROP 2 LAST NO_XNET_CONNECTION 1
J 0
(-2900 1950);
PAINT MONO (-2900 1950);
DISPLAY INVISIBLE (-2900 1950);
FORCEPROP 1 LASTPIN (-2800 1700) $PN 2
J 0
(-2815 1715);
DISPLAY 0.787234 (-2815 1715);
PAINT ORANGE (-2815 1715);
DISPLAY INVISIBLE (-2815 1715);
FORCEPROP 0 LAST BOM_COST ST_FLASH
J 0
(-2150 1800);
DISPLAY 1.021277 (-2150 1800);
PAINT ORANGE (-2150 1800);
DISPLAY INVISIBLE (-2150 1800);
FORCEPROP 0 LAST ROOM M_2
J 0
(-2150 1750);
DISPLAY 1.021277 (-2150 1750);
PAINT ORANGE (-2150 1750);
DISPLAY INVISIBLE (-2150 1750);
FORCEADD CAP..2
(-2900 1475);
FORCEPROP 1 LAST LOCATION C8F12
J 0
(-3400 1475);
DISPLAY 0.617021 (-3400 1475);
PAINT AQUA (-3400 1475);
FORCEPROP 1 LAST VALUE 0.22UF
J 1
(-3200 1475);
DISPLAY 0.617021 (-3200 1475);
PAINT SKYBLUE (-3200 1475);
FORCEPROP 1 LAST TOLERANCE 10%
J 2
(-3025 1475);
DISPLAY 0.617021 (-3025 1475);
PAINT SKYBLUE (-3025 1475);
FORCEPROP 1 LASTPIN (-3000 1475) $PN 1
J 0
(-3010 1490);
DISPLAY 0.617021 (-3010 1490);
PAINT ORANGE (-3010 1490);
FORCEPROP 1 LAST VOLTAGE 16V
J 0
(-2650 1475);
DISPLAY 0.617021 (-2650 1475);
PAINT SKYBLUE (-2650 1475);
FORCEPROP 1 LAST MATERIAL X7R
J 0
(-2750 1475);
DISPLAY 0.617021 (-2750 1475);
PAINT SKYBLUE (-2750 1475);
FORCEPROP 1 LASTPIN (-2800 1475) $PN 2
J 0
(-2815 1490);
DISPLAY 0.617021 (-2815 1490);
PAINT ORANGE (-2815 1490);
FORCEPROP 1 LAST PACK_TYPE 0402
J 2
(-2425 1475);
DISPLAY 0.617021 (-2425 1475);
PAINT SKYBLUE (-2425 1475);
FORCEPROP 1 LAST PART_NUMBER A36096-155
J 2
(-2150 1475);
DISPLAY 0.617021 (-2150 1475);
PAINT BLUE (-2150 1475);
FORCEPROP 2 LAST CDS_LOCATION C8F12
J 0
(-3400 1475);
DISPLAY 0.617021 (-3400 1475);
PAINT AQUA (-3400 1475);
DISPLAY INVISIBLE (-3400 1475);
FORCEPROP 2 LAST CDS_LIB mstr_discrete
J 0
(-2900 1475);
PAINT ORANGE (-2900 1475);
DISPLAY INVISIBLE (-2900 1475);
FORCEPROP 2 LAST SEC 1
J 0
(-2900 1725);
DISPLAY 0.680851 (-2900 1725);
PAINT MONO (-2900 1725);
DISPLAY INVISIBLE (-2900 1725);
FORCEPROP 2 LAST SEC_TYPE 0402
J 0
(-2900 1725);
DISPLAY 1.021277 (-2900 1725);
PAINT ORANGE (-2900 1725);
DISPLAY INVISIBLE (-2900 1725);
FORCEPROP 1 LAST PATH I98
J 0
(-2900 1675);
DISPLAY 0.978723 (-2900 1675);
PAINT WHITE (-2900 1675);
DISPLAY INVISIBLE (-2900 1675);
FORCEPROP 0 LAST ROOM M_2
J 0
(-2150 1525);
DISPLAY 1.021277 (-2150 1525);
PAINT ORANGE (-2150 1525);
DISPLAY INVISIBLE (-2150 1525);
FORCEPROP 0 LAST BOM_COST ST_FLASH
J 0
(-2150 1575);
DISPLAY 1.021277 (-2150 1575);
PAINT ORANGE (-2150 1575);
DISPLAY INVISIBLE (-2150 1575);
FORCEADD CAP_A..2
(-2900 1275);
FORCEPROP 1 LAST LOCATION C8F13
J 0
(-3400 1275);
DISPLAY 0.617021 (-3400 1275);
PAINT AQUA (-3400 1275);
FORCEPROP 1 LAST VALUE 0.01UF
J 2
(-3075 1175);
DISPLAY 0.617021 (-3075 1175);
PAINT SKYBLUE (-3075 1175);
FORCEPROP 1 LAST TOLERANCE 10%
J 2
(-2975 1175);
DISPLAY 0.617021 (-2975 1175);
PAINT SKYBLUE (-2975 1175);
FORCEPROP 1 LAST MATERIAL EMPTY
J 0
(-2750 1175);
DISPLAY 0.617021 (-2750 1175);
PAINT RED (-2750 1175);
FORCEPROP 1 LAST PART_NUMBER A36096-045
J 1
(-2550 1300);
DISPLAY 0.617021 (-2550 1300);
PAINT BLUE (-2550 1300);
FORCEPROP 1 LAST VOLTAGE 25V
J 0
(-2525 1175);
DISPLAY 0.617021 (-2525 1175);
PAINT SKYBLUE (-2525 1175);
FORCEPROP 1 LAST PACK_TYPE 0402V
J 1
(-2350 1175);
DISPLAY 0.617021 (-2350 1175);
PAINT SKYBLUE (-2350 1175);
FORCEPROP 2 LAST CDS_LOCATION C8F13
J 0
(-3400 1275);
DISPLAY 0.617021 (-3400 1275);
PAINT AQUA (-3400 1275);
DISPLAY INVISIBLE (-3400 1275);
FORCEPROP 2 LAST CDS_LIB dev_discrete
J 0
(-2900 1275);
PAINT ORANGE (-2900 1275);
DISPLAY INVISIBLE (-2900 1275);
FORCEPROP 1 LASTPIN (-3000 1275) $PN 1
J 0
(-3010 1290);
DISPLAY 0.787234 (-3010 1290);
PAINT ORANGE (-3010 1290);
DISPLAY INVISIBLE (-3010 1290);
FORCEPROP 1 LAST PATH I99
J 0
(-2900 1475);
DISPLAY 0.978723 (-2900 1475);
PAINT WHITE (-2900 1475);
DISPLAY INVISIBLE (-2900 1475);
FORCEPROP 1 LASTPIN (-2800 1275) $PN 2
J 0
(-2815 1290);
DISPLAY 0.787234 (-2815 1290);
PAINT ORANGE (-2815 1290);
DISPLAY INVISIBLE (-2815 1290);
FORCEPROP 2 LAST CDS_SEC 1
J 0
(-2900 1525);
PAINT MONO (-2900 1525);
DISPLAY INVISIBLE (-2900 1525);
FORCEPROP 2 LAST NO_XNET_CONNECTION 1
J 0
(-2900 1525);
PAINT MONO (-2900 1525);
DISPLAY INVISIBLE (-2900 1525);
FORCEPROP 0 LAST ROOM M_2
J 0
(-2150 1325);
DISPLAY 1.021277 (-2150 1325);
PAINT ORANGE (-2150 1325);
DISPLAY INVISIBLE (-2150 1325);
FORCEPROP 0 LAST BOM_COST ST_FLASH
J 0
(-2150 1375);
DISPLAY 1.021277 (-2150 1375);
PAINT ORANGE (-2150 1375);
DISPLAY INVISIBLE (-2150 1375);
FORCEADD DNS..2
(-2870 845);
PAINT RED (-2870 845);
FORCEPROP 1 LAST COMMENT_BODY TRUE
R 1
J 0
(-2795 620);
DISPLAY 0.872340 (-2795 620);
PAINT GREEN (-2795 620);
DISPLAY INVISIBLE (-2795 620);
FORCEPROP 2 LAST CDS_LIB mstr_misc
J 0
(-2870 845);
PAINT ORANGE (-2870 845);
DISPLAY INVISIBLE (-2870 845);
FORCEADD DNS..2
(-2895 2195);
PAINT RED (-2895 2195);
FORCEPROP 1 LAST COMMENT_BODY TRUE
R 1
J 0
(-2820 1970);
DISPLAY 0.872340 (-2820 1970);
PAINT GREEN (-2820 1970);
DISPLAY INVISIBLE (-2820 1970);
FORCEPROP 2 LAST CDS_LIB mstr_misc
J 0
(-2895 2195);
PAINT ORANGE (-2895 2195);
DISPLAY INVISIBLE (-2895 2195);
FORCEADD DNS..2
(-2895 1695);
PAINT RED (-2895 1695);
FORCEPROP 1 LAST COMMENT_BODY TRUE
R 1
J 0
(-2820 1470);
DISPLAY 0.872340 (-2820 1470);
PAINT GREEN (-2820 1470);
DISPLAY INVISIBLE (-2820 1470);
FORCEPROP 2 LAST CDS_LIB mstr_misc
J 0
(-2895 1695);
PAINT ORANGE (-2895 1695);
DISPLAY INVISIBLE (-2895 1695);
FORCEADD CAD_NOTE..1
(-7150 950);
FORCEPROP 0 LAST L1 PLACE CAP NEAR
J 0
(-7300 825);
DISPLAY 1.021277 (-7300 825);
PAINT ORANGE (-7300 825);
FORCEPROP 0 LAST L2 74LVC1G07 POWER PIN
J 0
(-7300 750);
DISPLAY 1.021277 (-7300 750);
PAINT ORANGE (-7300 750);
FORCEPROP 2 LAST CDS_LIB mstr_symbols
J 0
(-7150 950);
PAINT ORANGE (-7150 950);
DISPLAY INVISIBLE (-7150 950);
FORCEPROP 1 LAST COMMENT_BODY TRUE
J 0
(-7125 1050);
DISPLAY 0.978723 (-7125 1050);
PAINT ORANGE (-7125 1050);
DISPLAY INVISIBLE (-7125 1050);
FORCEADD CAD_NOTE..1
(-1400 3150);
FORCEPROP 0 LAST L1 PLACE CLOSE TO PINS 70,72,74
J 0
(-1550 3000);
DISPLAY 1.021277 (-1550 3000);
PAINT ORANGE (-1550 3000);
FORCEPROP 2 LAST CDS_LIB mstr_symbols
J 0
(-1400 3150);
PAINT MONO (-1400 3150);
DISPLAY INVISIBLE (-1400 3150);
FORCEPROP 1 LAST COMMENT_BODY TRUE
J 0
(-1375 3250);
DISPLAY 0.978723 (-1375 3250);
PAINT ORANGE (-1375 3250);
DISPLAY INVISIBLE (-1375 3250);
FORCEADD CAD_NOTE..1
(-1350 4875);
FORCEPROP 0 LAST L1 PLACE CLOSE TO PINS 2&4
J 0
(-1500 4725);
DISPLAY 1.021277 (-1500 4725);
PAINT ORANGE (-1500 4725);
FORCEPROP 2 LAST CDS_LIB mstr_symbols
J 0
(-1350 4875);
PAINT MONO (-1350 4875);
DISPLAY INVISIBLE (-1350 4875);
FORCEPROP 1 LAST COMMENT_BODY TRUE
J 0
(-1325 4975);
DISPLAY 0.978723 (-1325 4975);
PAINT ORANGE (-1325 4975);
DISPLAY INVISIBLE (-1325 4975);
FORCEADD CAD_NOTE..1
(-1350 4000);
FORCEPROP 0 LAST L1 PLACE CLOSE TO PINS 12,14,16,18
J 0
(-1500 3850);
DISPLAY 1.021277 (-1500 3850);
PAINT ORANGE (-1500 3850);
FORCEPROP 1 LAST COMMENT_BODY TRUE
J 0
(-1325 4100);
DISPLAY 0.978723 (-1325 4100);
PAINT ORANGE (-1325 4100);
DISPLAY INVISIBLE (-1325 4100);
FORCEPROP 2 LAST CDS_LIB mstr_symbols
J 0
(-1350 4000);
PAINT MONO (-1350 4000);
DISPLAY INVISIBLE (-1350 4000);
FORCEADD DESIGN_NOTE..1
(-5700 925);
FORCEPROP 2 LAST CDS_LIB mstr_symbols
J 0
(-5700 925);
PAINT ORANGE (-5700 925);
DISPLAY INVISIBLE (-5700 925);
FORCEPROP 1 LAST COMMENT_BODY TRUE
J 0
(-5675 1025);
DISPLAY 0.978723 (-5675 1025);
PAINT ORANGE (-5675 1025);
DISPLAY INVISIBLE (-5675 1025);
FORCEADD DNS..2
(-2895 1270);
PAINT RED (-2895 1270);
FORCEPROP 1 LAST COMMENT_BODY TRUE
R 1
J 0
(-2820 1045);
DISPLAY 0.872340 (-2820 1045);
PAINT GREEN (-2820 1045);
DISPLAY INVISIBLE (-2820 1045);
FORCEPROP 2 LAST CDS_LIB mstr_misc
J 0
(-2895 1270);
PAINT ORANGE (-2895 1270);
DISPLAY INVISIBLE (-2895 1270);
FORCEADD INTEL_CORP_BPAGE..1
(-125 0);
FORCEPROP 1 LAST CDS_CON_LAST_MODIFIED Tue Dec 01 11:52:16 2015
J 0
(-1550 325);
PAINT GREEN (-1550 325);
DISPLAY INVISIBLE (-1550 325);
FORCEPROP 1 LAST CUSTOM_TXT_CDS <CURRENT_DESIGN_SHEET> OF <TOTAL_DESIGN_SHEETS>
J 0
(-625 25);
PAINT GREEN (-625 25);
FORCEPROP 2 LAST CUSTOM_TXT_CDS <XR_PAGE_TITLE>
J 0
(-8015 5250);
DISPLAY 0.638298 (-8015 5250);
PAINT PINK (-8015 5250);
DISPLAY INVISIBLE (-8015 5250);
FORCEPROP 2 LAST CUSTOM_TXT_CDS <CON_LAST_MODIFIED>
J 0
(-2050 350);
PAINT GREEN (-2050 350);
FORCEPROP 1 LAST SCH_ADDRESS3 Santa Clara, CA 95052-8119
J 0
(-4100 25);
DISPLAY 0.617021 (-4100 25);
PAINT GREEN (-4100 25);
FORCEPROP 1 LAST SCH_ADDRESS2 P.O. BOX 58119
J 0
(-4100 75);
DISPLAY 0.617021 (-4100 75);
PAINT GREEN (-4100 75);
FORCEPROP 1 LAST SCH_TITLE M.2 CONNECTOR
J 0
(-8075 50);
DISPLAY 1.212766 (-8075 50);
PAINT ORANGE (-8075 50);
FORCEPROP 1 LAST SCH_REV 2.420
J 0
(-375 150);
DISPLAY 0.978723 (-375 150);
PAINT YELLOW (-375 150);
FORCEPROP 1 LAST SCH_DEPT BESD
J 1
(-4575 100);
DISPLAY 1.212766 (-4575 100);
PAINT YELLOW (-4575 100);
FORCEPROP 1 LAST SCH_NUMBER H4694802
J 0
(-1425 150);
DISPLAY 1.212766 (-1425 150);
PAINT YELLOW (-1425 150);
FORCEPROP 1 LAST SCH_ADDRESS1 2200 Mission College Blvd.
J 0
(-4100 125);
DISPLAY 0.617021 (-4100 125);
PAINT GREEN (-4100 125);
FORCEPROP 1 LAST COMMENT_BODY TRUE
J 0
(-113 12);
DISPLAY 0.468085 (-113 12);
PAINT GREEN (-113 12);
DISPLAY INVISIBLE (-113 12);
FORCEPROP 2 LAST PAGE_BORDER TRUE
J 0
(-8015 5250);
DISPLAY 0.617021 (-8015 5250);
PAINT PINK (-8015 5250);
DISPLAY INVISIBLE (-8015 5250);
FORCEPROP 2 LAST CDS_LIB mstr_symbols
J 0
(-125 0);
PAINT ORANGE (-125 0);
DISPLAY INVISIBLE (-125 0);
FORCEPROP 2 LAST CDS_XR_PAGE_TITLE CR-185 : @BASEBOARD_FAB2_LIB.BASEBOARD_FAB2(SCH_1):PAGE185
J 0
(-8015 5250);
DISPLAY 0.638298 (-8015 5250);
PAINT PINK (-8015 5250);
DISPLAY INVISIBLE (-8015 5250);
WIRE 16 -1 (-6725 1675)(-6725 1625);
WIRE 16 -1 (-6025 1675)(-6025 1625);
WIRE 16 -1 (-6425 800)(-6425 875);
WIRE 16 -1 (-6425 600)(-6425 525);
WIRE 16 -1 (-1150 4400)(-1150 4350);
WIRE 16 -1 (-1150 4350)(-1400 4350);
WIRE 16 -1 (-1400 4400)(-1400 4350);
WIRE 16 -1 (-1400 4350)(-1650 4350);
WIRE 16 -1 (-1650 4400)(-1650 4350);
WIRE 16 -1 (-1650 4350)(-1650 4325);
WIRE 16 -1 (-1400 4650)(-1150 4650);
WIRE 16 -1 (-1400 4650)(-1400 4600);
WIRE 16 -1 (-1650 4650)(-1400 4650);
WIRE 16 -1 (-1150 4650)(-1150 4600);
WIRE 16 -1 (-1650 4600)(-1650 4650);
WIRE 16 -1 (-1650 4650)(-1650 4675);
WIRE 16 -1 (-1150 3800)(-1150 3750);
WIRE 16 -1 (-1400 3800)(-1150 3800);
WIRE 16 -1 (-1400 3800)(-1400 3750);
WIRE 16 -1 (-1650 3800)(-1400 3800);
WIRE 16 -1 (-1650 3750)(-1650 3800);
WIRE 16 -1 (-1650 3800)(-1650 3825);
WIRE 16 -1 (-1150 3550)(-1150 3500);
WIRE 16 -1 (-1150 3500)(-1400 3500);
WIRE 16 -1 (-1400 3550)(-1400 3500);
WIRE 16 -1 (-1400 3500)(-1650 3500);
WIRE 16 -1 (-1650 3550)(-1650 3500);
WIRE 16 -1 (-1650 3500)(-1650 3475);
WIRE 16 -1 (-1150 2950)(-1150 2900);
WIRE 16 -1 (-1400 2950)(-1150 2950);
WIRE 16 -1 (-1400 2950)(-1400 2900);
WIRE 16 -1 (-1650 2950)(-1400 2950);
WIRE 16 -1 (-1650 2900)(-1650 2950);
WIRE 16 -1 (-1650 2950)(-1650 2975);
WIRE 16 -1 (-1150 2700)(-1150 2650);
WIRE 16 -1 (-1150 2650)(-1400 2650);
WIRE 16 -1 (-1400 2700)(-1400 2650);
WIRE 16 -1 (-1400 2650)(-1650 2650);
WIRE 16 -1 (-1650 2700)(-1650 2650);
WIRE 16 -1 (-1650 2650)(-1650 2625);
WIRE 16 -1 (-3300 3450)(-3300 3400);
WIRE 16 -1 (-5100 2925)(-5000 2925);
WIRE 16 -1 (-5000 2925)(-5000 2875);
WIRE 16 -1 (-5100 2875)(-5000 2875);
WIRE 16 -1 (-5000 2875)(-5000 2775);
WIRE 16 -1 (-5100 2775)(-5000 2775);
WIRE 16 -1 (-5000 2775)(-5000 2725);
WIRE 16 -1 (-5100 2725)(-5000 2725);
WIRE 16 -1 (-5000 2725)(-5000 2675);
WIRE 16 -1 (-5100 2675)(-5000 2675);
WIRE 16 -1 (-5000 2675)(-5000 2625);
WIRE 16 -1 (-5100 2625)(-5000 2625);
WIRE 16 -1 (-5000 2625)(-5000 2575);
WIRE 16 -1 (-5100 2575)(-5000 2575);
WIRE 16 -1 (-5000 2575)(-5000 2525);
WIRE 16 -1 (-5100 2525)(-5000 2525);
WIRE 16 -1 (-5000 2525)(-5000 2475);
WIRE 16 -1 (-5100 2475)(-5000 2475);
WIRE 16 -1 (-5000 2475)(-5000 2425);
WIRE 16 -1 (-5100 2425)(-5000 2425);
WIRE 16 -1 (-5000 2425)(-5000 2375);
WIRE 16 -1 (-5100 2375)(-5000 2375);
WIRE 16 -1 (-5000 2375)(-5000 2325);
WIRE 16 -1 (-5100 2325)(-5000 2325);
WIRE 16 -1 (-5000 2325)(-5000 2275);
WIRE 16 -1 (-5100 2275)(-5000 2275);
WIRE 16 -1 (-5000 2275)(-5000 2225);
WIRE 16 -1 (-5100 2225)(-5000 2225);
WIRE 16 -1 (-5000 2225)(-5000 2175);
WIRE 16 -1 (-5100 2175)(-5000 2175);
WIRE 16 -1 (-5000 2175)(-5000 2125);
WIRE 16 -1 (-5100 2125)(-5000 2125);
WIRE 16 -1 (-5000 2125)(-5000 1925);
WIRE 16 -1 (-6600 3875)(-6725 3875);
WIRE 16 -1 (-6725 3875)(-6725 3925);
WIRE 16 -1 (-6600 3925)(-6725 3925);
WIRE 16 -1 (-6725 3925)(-6725 3975);
WIRE 16 -1 (-6600 3975)(-6725 3975);
WIRE 16 -1 (-6725 3975)(-6725 4025);
WIRE 16 -1 (-6600 4025)(-6725 4025);
WIRE 16 -1 (-6725 4025)(-6725 4075);
WIRE 16 -1 (-6600 4075)(-6725 4075);
WIRE 16 -1 (-6725 4075)(-6725 4125);
WIRE 16 -1 (-6600 4125)(-6725 4125);
WIRE 16 -1 (-6725 4125)(-6725 4175);
WIRE 16 -1 (-6600 4175)(-6725 4175);
WIRE 16 -1 (-6725 4175)(-6725 4225);
WIRE 16 -1 (-6600 4225)(-6725 4225);
WIRE 16 -1 (-6725 4225)(-6725 4275);
WIRE 16 -1 (-6600 4275)(-6725 4275);
WIRE 16 -1 (-6725 4275)(-6725 4725);
WIRE 16 682 (-400 450)(-400 2425);
WIRE 16 682 (-4475 450)(-400 450);
WIRE 16 682 (-400 2425)(-4475 2425);
WIRE 16 682 (-4475 2425)(-4475 450);
WIRE 16 -1 (-5225 750)(-5225 650);
WIRE 16 -1 (-5225 850)(-5225 750);
WIRE 16 -1 (-5925 750)(-5225 750);
WIRE 16 -1 (-5225 650)(-5825 650);
WIRE 16 -1 (-5825 850)(-5825 650);
WIRE 16 -1 (-5825 650)(-5925 650);
WIRE 16 -1 (-5925 650)(-5925 750);
WIRE 16 -1 (-5925 850)(-5925 750);
WIRE 16 -1 (-5225 850)(-5825 850);
WIRE 16 -1 (-5825 850)(-5925 850);
WIRE 16 -1 (-3825 2200)(-3000 2200);
FORCEPROP 2 LAST SIG_NAME SATA6G_S0_TX_DP
J 0
(-3810 2210);
DISPLAY 0.617021 (-3810 2210);
PAINT ORANGE (-3810 2210);
WIRE 16 -1 (-2800 2200)(-2050 2200);
WIRE 16 -1 (-2050 2200)(-1500 2200);
FORCEPROP 2 LAST SIG_NAME P3E_PCH_M2_SATA6G_TX_R_DP
J 2
(-1525 2210);
DISPLAY 0.617021 (-1525 2210);
PAINT ORANGE (-1525 2210);
WIRE 16 -1 (-2050 1925)(-2050 2200);
WIRE 16 -1 (-2800 1925)(-2050 1925);
WIRE 16 -1 (-3850 3875)(-2650 3875);
FORCEPROP 2 LAST SIG_NAME P3E_PCH_M2_TX_DN<2>
J 2
(-2675 3885);
DISPLAY 0.617021 (-2675 3885);
PAINT ORANGE (-2675 3885);
WIRE 16 -1 (-5100 3925)(-4050 3925);
FORCEPROP 2 LAST SIG_NAME P3E_PCH_M2_TX_C_DP<2>
J 0
(-5000 3935);
DISPLAY 0.617021 (-5000 3935);
PAINT ORANGE (-5000 3935);
FORCEPROP 2 LASTPROP $XRERR UNIQUE?
J 0
(-5240 3935);
DISPLAY 0.638298 (-5240 3935);
PAINT MONO (-5240 3935);
DISPLAY INVISIBLE (-5240 3935);
WIRE 16 -1 (-5100 4125)(-4050 4125);
FORCEPROP 2 LAST SIG_NAME P3E_PCH_M2_TX_C_DN<3>
J 0
(-5000 4135);
DISPLAY 0.617021 (-5000 4135);
PAINT ORANGE (-5000 4135);
FORCEPROP 2 LASTPROP $XRERR UNIQUE?
J 0
(-5240 4135);
DISPLAY 0.638298 (-5240 4135);
PAINT MONO (-5240 4135);
DISPLAY INVISIBLE (-5240 4135);
WIRE 16 -1 (-3850 4125)(-2650 4125);
FORCEPROP 2 LAST SIG_NAME P3E_PCH_M2_TX_DN<3>
J 2
(-2675 4135);
DISPLAY 0.617021 (-2675 4135);
PAINT ORANGE (-2675 4135);
WIRE 16 -1 (-3850 4175)(-2650 4175);
FORCEPROP 2 LAST SIG_NAME P3E_PCH_M2_TX_DP<3>
J 2
(-2675 4185);
DISPLAY 0.617021 (-2675 4185);
PAINT ORANGE (-2675 4185);
WIRE 16 -1 (-2075 850)(-1500 850);
FORCEPROP 2 LAST SIG_NAME P3E_PCH_M2_SATA6G_RX_R_DN
J 2
(-1550 860);
DISPLAY 0.617021 (-1550 860);
PAINT ORANGE (-1550 860);
WIRE 16 -1 (-2075 600)(-2075 850);
WIRE 16 -1 (-2775 850)(-2075 850);
WIRE 16 -1 (-2775 600)(-2075 600);
WIRE 16 -1 (-2075 1275)(-1500 1275);
FORCEPROP 2 LAST SIG_NAME P3E_PCH_M2_SATA6G_RX_R_DP
J 2
(-1550 1285);
DISPLAY 0.617021 (-1550 1285);
PAINT ORANGE (-1550 1285);
WIRE 16 -1 (-2075 1050)(-2075 1275);
WIRE 16 -1 (-2800 1275)(-2075 1275);
WIRE 16 -1 (-2800 1050)(-2075 1050);
WIRE 16 -1 (-2075 1700)(-1500 1700);
FORCEPROP 2 LAST SIG_NAME P3E_PCH_M2_SATA6G_TX_R_DN
J 2
(-1525 1710);
DISPLAY 0.617021 (-1525 1710);
PAINT ORANGE (-1525 1710);
WIRE 16 -1 (-2075 1475)(-2075 1700);
WIRE 16 -1 (-2800 1700)(-2075 1700);
WIRE 16 -1 (-2800 1475)(-2075 1475);
WIRE 16 -1 (-3850 3675)(-2650 3675);
FORCEPROP 2 LAST SIG_NAME P3E_PCH_M2_TX_DP<1>
J 2
(-2675 3685);
DISPLAY 0.617021 (-2675 3685);
PAINT ORANGE (-2675 3685);
WIRE 16 -1 (-3850 3625)(-2650 3625);
FORCEPROP 2 LAST SIG_NAME P3E_PCH_M2_TX_DN<1>
J 2
(-2675 3635);
DISPLAY 0.617021 (-2675 3635);
PAINT ORANGE (-2675 3635);
WIRE 16 -1 (-3850 3925)(-2650 3925);
FORCEPROP 2 LAST SIG_NAME P3E_PCH_M2_TX_DP<2>
J 2
(-2675 3935);
DISPLAY 0.617021 (-2675 3935);
PAINT ORANGE (-2675 3935);
WIRE 16 -1 (-3300 3200)(-3300 3075);
WIRE 16 -1 (-3775 3075)(-3300 3075);
WIRE 16 -1 (-3775 3225)(-3775 3075);
WIRE 16 -1 (-5100 3225)(-3775 3225);
FORCEPROP 0 LAST SIG_NAME PU_M2_CLK_REQ_N
J 0
(-5000 3235);
DISPLAY 0.617021 (-5000 3235);
PAINT ORANGE (-5000 3235);
FORCEPROP 2 LASTPROP $XRERR UNIQUE?
J 0
(-5240 3235);
DISPLAY 0.638298 (-5240 3235);
PAINT MONO (-5240 3235);
DISPLAY INVISIBLE (-5240 3235);
WIRE 16 -1 (-2975 600)(-3825 600);
FORCEPROP 2 LAST SIG_NAME P3E_PCH_RX_0_DN
J 0
(-3785 610);
DISPLAY 0.617021 (-3785 610);
PAINT ORANGE (-3785 610);
WIRE 16 -1 (-3825 850)(-2975 850);
FORCEPROP 2 LAST SIG_NAME SATA6G_S0_RX_DN
J 0
(-3785 860);
DISPLAY 0.617021 (-3785 860);
PAINT ORANGE (-3785 860);
WIRE 16 -1 (-3000 1050)(-3825 1050);
FORCEPROP 2 LAST SIG_NAME P3E_PCH_RX_0_DP
J 0
(-3785 1060);
DISPLAY 0.617021 (-3785 1060);
PAINT ORANGE (-3785 1060);
WIRE 16 -1 (-3825 1275)(-3000 1275);
FORCEPROP 2 LAST SIG_NAME SATA6G_S0_RX_DP
J 0
(-3785 1285);
DISPLAY 0.617021 (-3785 1285);
PAINT ORANGE (-3785 1285);
WIRE 16 -1 (-3000 1475)(-3825 1475);
FORCEPROP 2 LAST SIG_NAME P3E_PCH_TX_0_DN
J 0
(-3810 1485);
DISPLAY 0.617021 (-3810 1485);
PAINT ORANGE (-3810 1485);
WIRE 16 -1 (-3825 1700)(-3000 1700);
FORCEPROP 2 LAST SIG_NAME SATA6G_S0_TX_DN
J 0
(-3785 1710);
DISPLAY 0.617021 (-3785 1710);
PAINT ORANGE (-3785 1710);
WIRE 16 -1 (-3000 1925)(-3825 1925);
FORCEPROP 2 LAST SIG_NAME P3E_PCH_TX_0_DP
J 0
(-3785 1935);
DISPLAY 0.617021 (-3785 1935);
PAINT ORANGE (-3785 1935);
WIRE 16 -1 (-5100 3875)(-4050 3875);
FORCEPROP 2 LAST SIG_NAME P3E_PCH_M2_TX_C_DN<2>
J 0
(-5000 3885);
DISPLAY 0.617021 (-5000 3885);
PAINT ORANGE (-5000 3885);
FORCEPROP 2 LASTPROP $XRERR UNIQUE?
J 0
(-5240 3885);
DISPLAY 0.638298 (-5240 3885);
PAINT MONO (-5240 3885);
DISPLAY INVISIBLE (-5240 3885);
WIRE 16 -1 (-5100 4175)(-4050 4175);
FORCEPROP 2 LAST SIG_NAME P3E_PCH_M2_TX_C_DP<3>
J 0
(-5000 4185);
DISPLAY 0.617021 (-5000 4185);
PAINT ORANGE (-5000 4185);
FORCEPROP 2 LASTPROP $XRERR UNIQUE?
J 0
(-5240 4185);
DISPLAY 0.638298 (-5240 4185);
PAINT MONO (-5240 4185);
DISPLAY INVISIBLE (-5240 4185);
WIRE 16 -1 (-5100 3625)(-4050 3625);
FORCEPROP 2 LAST SIG_NAME P3E_PCH_M2_TX_C_DN<1>
J 0
(-5000 3635);
DISPLAY 0.617021 (-5000 3635);
PAINT ORANGE (-5000 3635);
FORCEPROP 2 LASTPROP $XRERR UNIQUE?
J 0
(-5240 3635);
DISPLAY 0.638298 (-5240 3635);
PAINT MONO (-5240 3635);
DISPLAY INVISIBLE (-5240 3635);
WIRE 16 -1 (-5100 3675)(-4050 3675);
FORCEPROP 2 LAST SIG_NAME P3E_PCH_M2_TX_C_DP<1>
J 0
(-5000 3685);
DISPLAY 0.617021 (-5000 3685);
PAINT ORANGE (-5000 3685);
FORCEPROP 2 LASTPROP $XRERR UNIQUE?
J 0
(-5240 3685);
DISPLAY 0.638298 (-5240 3685);
PAINT MONO (-5240 3685);
DISPLAY INVISIBLE (-5240 3685);
WIRE 16 -1 (-5100 3725)(-2650 3725);
FORCEPROP 2 LAST SIG_NAME P3E_PCH_M2_RX_DN<1>
J 2
(-2675 3735);
DISPLAY 0.617021 (-2675 3735);
PAINT ORANGE (-2675 3735);
WIRE 16 -1 (-5100 3775)(-2650 3775);
FORCEPROP 2 LAST SIG_NAME P3E_PCH_M2_RX_DP<1>
J 2
(-2675 3785);
DISPLAY 0.617021 (-2675 3785);
PAINT ORANGE (-2675 3785);
WIRE 16 -1 (-5100 3975)(-2650 3975);
FORCEPROP 2 LAST SIG_NAME P3E_PCH_M2_RX_DN<2>
J 2
(-2675 3985);
DISPLAY 0.617021 (-2675 3985);
PAINT ORANGE (-2675 3985);
WIRE 16 -1 (-5100 4025)(-2650 4025);
FORCEPROP 2 LAST SIG_NAME P3E_PCH_M2_RX_DP<2>
J 2
(-2675 4035);
DISPLAY 0.617021 (-2675 4035);
PAINT ORANGE (-2675 4035);
WIRE 16 -1 (-2650 4225)(-5100 4225);
FORCEPROP 2 LAST SIG_NAME P3E_PCH_M2_RX_DN<3>
J 2
(-2675 4235);
DISPLAY 0.617021 (-2675 4235);
PAINT ORANGE (-2675 4235);
WIRE 16 -1 (-5100 4275)(-2650 4275);
FORCEPROP 2 LAST SIG_NAME P3E_PCH_M2_RX_DP<3>
J 2
(-2675 4285);
DISPLAY 0.617021 (-2675 4285);
PAINT ORANGE (-2675 4285);
WIRE 16 -1 (-5100 3425)(-4450 3425);
FORCEPROP 2 LAST SIG_NAME TP_M2_DEVSLP
J 0
(-5000 3435);
DISPLAY 0.617021 (-5000 3435);
PAINT ORANGE (-5000 3435);
FORCEPROP 2 LASTPROP $XRERR UNIQUE?
J 0
(-4420 3425);
DISPLAY 0.638298 (-4420 3425);
PAINT MONO (-4420 3425);
DISPLAY INVISIBLE (-4420 3425);
WIRE 16 -1 (-5100 3525)(-4450 3525);
FORCEPROP 0 LAST SIG_NAME TP_M2_32M_SUSCLK
J 0
(-5000 3535);
DISPLAY 0.617021 (-5000 3535);
PAINT ORANGE (-5000 3535);
FORCEPROP 2 LASTPROP $XRERR UNIQUE?
J 0
(-4420 3525);
DISPLAY 0.638298 (-4420 3525);
PAINT MONO (-4420 3525);
DISPLAY INVISIBLE (-4420 3525);
WIRE 16 -1 (-5100 3175)(-4450 3175);
FORCEPROP 0 LAST SIG_NAME FM_PE_M2_WAKE_N
J 0
(-5000 3185);
DISPLAY 0.617021 (-5000 3185);
PAINT ORANGE (-5000 3185);
WIRE 16 -1 (-5100 3325)(-4450 3325);
FORCEPROP 0 LAST SIG_NAME RST_PCIE_M2_DEV_N
J 0
(-5000 3335);
DISPLAY 0.617021 (-5000 3335);
PAINT ORANGE (-5000 3335);
WIRE 16 -1 (-5100 3075)(-4450 3075);
FORCEPROP 0 LAST SIG_NAME CLK_100M_M2_DP
J 0
(-5000 3085);
DISPLAY 0.617021 (-5000 3085);
PAINT ORANGE (-5000 3085);
WIRE 16 -1 (-5100 3025)(-4450 3025);
FORCEPROP 0 LAST SIG_NAME CLK_100M_M2_DN
J 0
(-5000 3035);
DISPLAY 0.617021 (-5000 3035);
PAINT ORANGE (-5000 3035);
WIRE 16 -1 (-5550 1250)(-5000 1250);
FORCEPROP 0 LAST SIG_NAME FM_SSATA_PCIE_M2_SEL
J 0
(-5485 1260);
DISPLAY 0.617021 (-5485 1260);
PAINT ORANGE (-5485 1260);
WIRE 16 -1 (-6025 1250)(-5750 1250);
WIRE 16 -1 (-6025 1425)(-6025 1250);
FORCEPROP 0 LAST SIG_NAME FM_M2_DET_LVC3
J 0
(-6160 1260);
DISPLAY 0.617021 (-6160 1260);
PAINT ORANGE (-6160 1260);
FORCEPROP 2 LASTPROP $XRERR UNIQUE?
J 0
(-6400 1260);
DISPLAY 0.638298 (-6400 1260);
PAINT MONO (-6400 1260);
DISPLAY INVISIBLE (-6400 1260);
WIRE 16 -1 (-6025 1250)(-6225 1250);
WIRE 16 -1 (-6600 2075)(-7000 2075);
FORCEPROP 2 LAST SIG_NAME NC_M2<0>
J 0
(-6985 2085);
DISPLAY 0.617021 (-6985 2085);
PAINT ORANGE (-6985 2085);
FORCEPROP 2 LASTPROP $XRERR UNIQUE?
J 0
(-7240 2075);
DISPLAY 0.638298 (-7240 2075);
PAINT MONO (-7240 2075);
DISPLAY INVISIBLE (-7240 2075);
WIRE 16 -1 (-6600 2425)(-7000 2425);
FORCEPROP 2 LAST SIG_NAME NC_M2<7>
J 0
(-6985 2435);
DISPLAY 0.617021 (-6985 2435);
PAINT ORANGE (-6985 2435);
FORCEPROP 2 LASTPROP $XRERR UNIQUE?
J 0
(-7240 2425);
DISPLAY 0.638298 (-7240 2425);
PAINT MONO (-7240 2425);
DISPLAY INVISIBLE (-7240 2425);
WIRE 16 -1 (-6600 2375)(-7000 2375);
FORCEPROP 2 LAST SIG_NAME NC_M2<6>
J 0
(-6985 2385);
DISPLAY 0.617021 (-6985 2385);
PAINT ORANGE (-6985 2385);
FORCEPROP 2 LASTPROP $XRERR UNIQUE?
J 0
(-7240 2375);
DISPLAY 0.638298 (-7240 2375);
PAINT MONO (-7240 2375);
DISPLAY INVISIBLE (-7240 2375);
WIRE 16 -1 (-6600 2475)(-7000 2475);
FORCEPROP 2 LAST SIG_NAME NC_M2<8>
J 0
(-6985 2485);
DISPLAY 0.617021 (-6985 2485);
PAINT ORANGE (-6985 2485);
FORCEPROP 2 LASTPROP $XRERR UNIQUE?
J 0
(-7240 2475);
DISPLAY 0.638298 (-7240 2475);
PAINT MONO (-7240 2475);
DISPLAY INVISIBLE (-7240 2475);
WIRE 16 -1 (-6600 2325)(-7000 2325);
FORCEPROP 2 LAST SIG_NAME NC_M2<5>
J 0
(-6985 2335);
DISPLAY 0.617021 (-6985 2335);
PAINT ORANGE (-6985 2335);
FORCEPROP 2 LASTPROP $XRERR UNIQUE?
J 0
(-7240 2325);
DISPLAY 0.638298 (-7240 2325);
PAINT MONO (-7240 2325);
DISPLAY INVISIBLE (-7240 2325);
WIRE 16 -1 (-6600 2125)(-7000 2125);
FORCEPROP 2 LAST SIG_NAME NC_M2<1>
J 0
(-6985 2135);
DISPLAY 0.617021 (-6985 2135);
PAINT ORANGE (-6985 2135);
FORCEPROP 2 LASTPROP $XRERR UNIQUE?
J 0
(-7240 2125);
DISPLAY 0.638298 (-7240 2125);
PAINT MONO (-7240 2125);
DISPLAY INVISIBLE (-7240 2125);
WIRE 16 -1 (-6600 2175)(-7000 2175);
FORCEPROP 2 LAST SIG_NAME NC_M2<2>
J 0
(-6985 2185);
DISPLAY 0.617021 (-6985 2185);
PAINT ORANGE (-6985 2185);
FORCEPROP 2 LASTPROP $XRERR UNIQUE?
J 0
(-7240 2175);
DISPLAY 0.638298 (-7240 2175);
PAINT MONO (-7240 2175);
DISPLAY INVISIBLE (-7240 2175);
WIRE 16 -1 (-6600 2225)(-7000 2225);
FORCEPROP 2 LAST SIG_NAME NC_M2<3>
J 0
(-6985 2235);
DISPLAY 0.617021 (-6985 2235);
PAINT ORANGE (-6985 2235);
FORCEPROP 2 LASTPROP $XRERR UNIQUE?
J 0
(-7240 2225);
DISPLAY 0.638298 (-7240 2225);
PAINT MONO (-7240 2225);
DISPLAY INVISIBLE (-7240 2225);
WIRE 16 -1 (-6600 2275)(-7000 2275);
FORCEPROP 2 LAST SIG_NAME NC_M2<4>
J 0
(-6985 2285);
DISPLAY 0.617021 (-6985 2285);
PAINT ORANGE (-6985 2285);
FORCEPROP 2 LASTPROP $XRERR UNIQUE?
J 0
(-7240 2275);
DISPLAY 0.638298 (-7240 2275);
PAINT MONO (-7240 2275);
DISPLAY INVISIBLE (-7240 2275);
WIRE 16 -1 (-6600 2975)(-7000 2975);
FORCEPROP 2 LAST SIG_NAME NC_M2<18>
J 0
(-6985 2985);
DISPLAY 0.617021 (-6985 2985);
PAINT ORANGE (-6985 2985);
FORCEPROP 2 LASTPROP $XRERR UNIQUE?
J 0
(-7240 2975);
DISPLAY 0.638298 (-7240 2975);
PAINT MONO (-7240 2975);
DISPLAY INVISIBLE (-7240 2975);
WIRE 16 -1 (-6600 2525)(-7000 2525);
FORCEPROP 2 LAST SIG_NAME NC_M2<9>
J 0
(-6985 2535);
DISPLAY 0.617021 (-6985 2535);
PAINT ORANGE (-6985 2535);
FORCEPROP 2 LASTPROP $XRERR UNIQUE?
J 0
(-7240 2525);
DISPLAY 0.638298 (-7240 2525);
PAINT MONO (-7240 2525);
DISPLAY INVISIBLE (-7240 2525);
WIRE 16 -1 (-6600 2575)(-7000 2575);
FORCEPROP 2 LAST SIG_NAME NC_M2<10>
J 0
(-6985 2585);
DISPLAY 0.617021 (-6985 2585);
PAINT ORANGE (-6985 2585);
FORCEPROP 2 LASTPROP $XRERR UNIQUE?
J 0
(-7240 2575);
DISPLAY 0.638298 (-7240 2575);
PAINT MONO (-7240 2575);
DISPLAY INVISIBLE (-7240 2575);
WIRE 16 -1 (-6600 2625)(-7000 2625);
FORCEPROP 2 LAST SIG_NAME NC_M2<11>
J 0
(-6985 2635);
DISPLAY 0.617021 (-6985 2635);
PAINT ORANGE (-6985 2635);
FORCEPROP 2 LASTPROP $XRERR UNIQUE?
J 0
(-7240 2625);
DISPLAY 0.638298 (-7240 2625);
PAINT MONO (-7240 2625);
DISPLAY INVISIBLE (-7240 2625);
WIRE 16 -1 (-6600 2675)(-7000 2675);
FORCEPROP 2 LAST SIG_NAME NC_M2<12>
J 0
(-6985 2685);
DISPLAY 0.617021 (-6985 2685);
PAINT ORANGE (-6985 2685);
FORCEPROP 2 LASTPROP $XRERR UNIQUE?
J 0
(-7240 2675);
DISPLAY 0.638298 (-7240 2675);
PAINT MONO (-7240 2675);
DISPLAY INVISIBLE (-7240 2675);
WIRE 16 -1 (-6600 2725)(-7000 2725);
FORCEPROP 2 LAST SIG_NAME NC_M2<13>
J 0
(-6985 2735);
DISPLAY 0.617021 (-6985 2735);
PAINT ORANGE (-6985 2735);
FORCEPROP 2 LASTPROP $XRERR UNIQUE?
J 0
(-7240 2725);
DISPLAY 0.638298 (-7240 2725);
PAINT MONO (-7240 2725);
DISPLAY INVISIBLE (-7240 2725);
WIRE 16 -1 (-6600 2775)(-7000 2775);
FORCEPROP 2 LAST SIG_NAME NC_M2<14>
J 0
(-6985 2785);
DISPLAY 0.617021 (-6985 2785);
PAINT ORANGE (-6985 2785);
FORCEPROP 2 LASTPROP $XRERR UNIQUE?
J 0
(-7240 2775);
DISPLAY 0.638298 (-7240 2775);
PAINT MONO (-7240 2775);
DISPLAY INVISIBLE (-7240 2775);
WIRE 16 -1 (-6600 2825)(-7000 2825);
FORCEPROP 2 LAST SIG_NAME NC_M2<15>
J 0
(-6985 2835);
DISPLAY 0.617021 (-6985 2835);
PAINT ORANGE (-6985 2835);
FORCEPROP 2 LASTPROP $XRERR UNIQUE?
J 0
(-7240 2825);
DISPLAY 0.638298 (-7240 2825);
PAINT MONO (-7240 2825);
DISPLAY INVISIBLE (-7240 2825);
WIRE 16 -1 (-6600 2875)(-7000 2875);
FORCEPROP 2 LAST SIG_NAME NC_M2<16>
J 0
(-6985 2885);
DISPLAY 0.617021 (-6985 2885);
PAINT ORANGE (-6985 2885);
FORCEPROP 2 LASTPROP $XRERR UNIQUE?
J 0
(-7240 2875);
DISPLAY 0.638298 (-7240 2875);
PAINT MONO (-7240 2875);
DISPLAY INVISIBLE (-7240 2875);
WIRE 16 -1 (-6600 2925)(-7000 2925);
FORCEPROP 2 LAST SIG_NAME NC_M2<17>
J 0
(-6985 2935);
DISPLAY 0.617021 (-6985 2935);
PAINT ORANGE (-6985 2935);
FORCEPROP 2 LASTPROP $XRERR UNIQUE?
J 0
(-7240 2925);
DISPLAY 0.638298 (-7240 2925);
PAINT MONO (-7240 2925);
DISPLAY INVISIBLE (-7240 2925);
WIRE 16 -1 (-6600 3175)(-7275 3175);
FORCEPROP 0 LAST SIG_NAME FM_M2_SSD_PEDET
J 0
(-7250 3185);
DISPLAY 0.617021 (-7250 3185);
PAINT ORANGE (-7250 3185);
FORCEPROP 2 LASTPROP $XRERR UNIQUE?
J 0
(-7490 3185);
DISPLAY 0.638298 (-7490 3185);
PAINT MONO (-7490 3185);
DISPLAY INVISIBLE (-7490 3185);
WIRE 16 -1 (-7275 1250)(-7275 3175);
WIRE 16 -1 (-6725 1250)(-7275 1250);
WIRE 16 -1 (-6725 1250)(-6475 1250);
WIRE 16 -1 (-6725 1425)(-6725 1250);
WIRE 16 -1 (-7625 3325)(-6600 3325);
FORCEPROP 0 LAST SIG_NAME TP_LED_M2_ACT_N
J 0
(-7625 3335);
DISPLAY 0.617021 (-7625 3335);
PAINT ORANGE (-7625 3335);
FORCEPROP 2 LASTPROP $XRERR UNIQUE?
J 0
(-7865 3325);
DISPLAY 0.638298 (-7865 3325);
PAINT MONO (-7865 3325);
DISPLAY INVISIBLE (-7865 3325);
WIRE 16 -1 (-6600 3675)(-7625 3675);
FORCEPROP 2 LAST SIG_NAME P3E_PCH_M2_SATA6G_RX_R_DP
J 0
(-7625 3685);
DISPLAY 0.617021 (-7625 3685);
PAINT ORANGE (-7625 3685);
WIRE 16 -1 (-6600 3725)(-7625 3725);
FORCEPROP 2 LAST SIG_NAME P3E_PCH_M2_SATA6G_RX_R_DN
J 0
(-7625 3735);
DISPLAY 0.617021 (-7625 3735);
PAINT ORANGE (-7625 3735);
WIRE 16 -1 (-6600 3525)(-7625 3525);
FORCEPROP 2 LAST SIG_NAME P3E_PCH_M2_SATA6G_TX_R_DP
J 0
(-7625 3535);
DISPLAY 0.617021 (-7625 3535);
PAINT ORANGE (-7625 3535);
WIRE 16 -1 (-6600 3475)(-7625 3475);
DOT 1 (-2050 2200);
DOT 1 (-2075 1700);
DOT 1 (-2075 1275);
DOT 1 (-2075 850);
DOT 1 (-6725 4275);
DOT 1 (-6725 4225);
DOT 1 (-6725 4125);
DOT 1 (-6725 4175);
DOT 1 (-5000 2875);
DOT 1 (-5000 2775);
DOT 1 (-5000 2725);
DOT 1 (-5000 2575);
DOT 1 (-5000 2625);
DOT 1 (-5000 2675);
DOT 1 (-5000 2475);
DOT 1 (-5000 2525);
DOT 1 (-5000 2325);
DOT 1 (-5000 2425);
DOT 1 (-5000 2375);
DOT 1 (-5000 2275);
DOT 1 (-5000 2225);
DOT 1 (-5000 2175);
DOT 1 (-5000 2125);
DOT 1 (-6025 1250);
DOT 1 (-5225 750);
DOT 1 (-5825 850);
DOT 1 (-5825 650);
DOT 1 (-6725 4075);
DOT 1 (-6725 4025);
DOT 1 (-6725 3975);
DOT 1 (-6725 3925);
DOT 1 (-6725 1250);
DOT 1 (-1400 4650);
DOT 1 (-1650 4650);
DOT 1 (-1400 4350);
DOT 1 (-1650 4350);
DOT 1 (-1400 3800);
DOT 1 (-1650 3800);
DOT 1 (-1400 3500);
DOT 1 (-1650 3500);
DOT 1 (-1400 2950);
DOT 1 (-1400 2650);
DOT 1 (-1650 2950);
DOT 1 (-1650 2650);
DOT 1 (-5925 750);
FORCENOTE
POP_M2_SATA
(-3025 2275) 0;
DISPLAY LEFT (-3025 2275);
DISPLAY 0.638298 (-3025 2275);
PAINT PURPLE (-3025 2275);
FORCENOTE
POP_M2_PCIE
(-3050 2000) 0;
DISPLAY LEFT (-3050 2000);
DISPLAY 0.638298 (-3050 2000);
PAINT PURPLE (-3050 2000);
FORCENOTE
POP_M2_PCIE
(-3050 1550) 0;
DISPLAY LEFT (-3050 1550);
DISPLAY 0.638298 (-3050 1550);
PAINT PURPLE (-3050 1550);
FORCENOTE
POP_M2_SATA
(-3025 1375) 0;
DISPLAY LEFT (-3025 1375);
DISPLAY 0.638298 (-3025 1375);
PAINT PURPLE (-3025 1375);
FORCENOTE
POP_M2_PCIE
(-3025 1125) 0;
DISPLAY LEFT (-3025 1125);
DISPLAY 0.638298 (-3025 1125);
PAINT PURPLE (-3025 1125);
FORCENOTE
POP_M2_SATA
(-3000 975) 0;
DISPLAY LEFT (-3000 975);
DISPLAY 0.638298 (-3000 975);
PAINT PURPLE (-3000 975);
FORCENOTE
POP_M2_PCIE
(-3000 650) 0;
DISPLAY LEFT (-3000 650);
DISPLAY 0.638298 (-3000 650);
PAINT PURPLE (-3000 650);
FORCENOTE
0  M.2 SATA SSD
(-5900 775) 0;
DISPLAY LEFT (-5900 775);
DISPLAY 1.021277 (-5900 775);
PAINT PURPLE (-5900 775);
FORCENOTE
BOM_COST=ST_FLASH
(-7950 225) 0;
DISPLAY LEFT (-7950 225);
DISPLAY 1.021277 (-7950 225);
PAINT PURPLE (-7950 225);
FORCENOTE
ROOM=M_2
(-7950 325) 0;
DISPLAY LEFT (-7950 325);
DISPLAY 1.021277 (-7950 325);
PAINT PURPLE (-7950 325);
FORCENOTE
M.2 CONNECTOR
(-1350 1425) 0;
DISPLAY LEFT (-1350 1425);
DISPLAY 1.595745 (-1350 1425);
PAINT PURPLE (-1350 1425);
FORCENOTE
POP_M2_SATA
(-3025 1825) 0;
DISPLAY LEFT (-3025 1825);
DISPLAY 0.638298 (-3025 1825);
PAINT PURPLE (-3025 1825);
FORCENOTE
1  M.2 PCIE SSD
(-5900 675) 0;
DISPLAY LEFT (-5900 675);
DISPLAY 1.021277 (-5900 675);
PAINT PURPLE (-5900 675);
FORCENOTE
PCH
(-4400 1375) 0;
DISPLAY LEFT (-4400 1375);
DISPLAY 1.595745 (-4400 1375);
PAINT PURPLE (-4400 1375);
QUIT
